G04 ================== begin FILE IDENTIFICATION RECORD ==================*
G04 Layout Name:  D:/<user>/Wistron_project/16315-1/gbr/16315-1.brd*
G04 Film Name:    L9GND*
G04 File Format:  Gerber RS274X*
G04 File Origin:  Cadence Allegro 16.5-S056*
G04 Origin Date:  Fri Jun 09 15:31:59 2017*
G04 *
G04 Layer:  VIA CLASS/L9GND*
G04 Layer:  PIN/L9GND*
G04 Layer:  ETCH/L9GND*
G04 Layer:  DRAWING FORMAT/LAYER_PCB_STORY*
G04 Layer:  DRAWING FORMAT/LAYER_L9GND*
G04 *
G04 Offset:    (0.00 0.00)*
G04 Mirror:    No*
G04 Mode:      Negative*
G04 Rotation:  0*
G04 FullContactRelief:  No*
G04 UndefLineWidth:     6.00*
G04 ================== end FILE IDENTIFICATION RECORD ====================*
%FSLAX35Y35*MOIN*%
%IR0*IPPOS*OFA0.00000B0.00000*MIA0B0*SFA1.00000B1.00000*%
%ADD24C,.03*%
%ADD43C,.04*%
%ADD14C,.032*%
%ADD41C,.052*%
%ADD32C,.043*%
%ADD22C,.036*%
%ADD20C,.081*%
%ADD19C,.065*%
%ADD37C,.057*%
%ADD42C,.058*%
%AMMACRO31*
4,1,15,.00398,.00044,
.003999,.000208,
.004004,-.000025,
.003996,-.000258,
.00398,-.00044,
.00483,-.00129,
.004897,-.001007,
.004947,-.000721,
.004981,-.000432,
.004997,-.000141,
.004997,.000149,
.00498,.00044,
.004946,.000729,
.004895,.001015,
.00483,.00129,
.00398,.00044,
90.*
4,1,15,.00044,-.00398,
.000208,-.003999,
-.000025,-.004004,
-.000258,-.003996,
-.00044,-.00398,
-.00129,-.00483,
-.001007,-.004897,
-.000721,-.004947,
-.000432,-.004981,
-.000141,-.004997,
.000149,-.004997,
.00044,-.00498,
.000729,-.004946,
.001015,-.004895,
.00129,-.00483,
.00044,-.00398,
90.*
4,1,15,-.00398,-.00044,
-.003999,-.000208,
-.004004,.000025,
-.003996,.000258,
-.00398,.00044,
-.00483,.00129,
-.004897,.001007,
-.004947,.000721,
-.004981,.000432,
-.004997,.000141,
-.004997,-.000149,
-.00498,-.00044,
-.004946,-.000729,
-.004895,-.001015,
-.00483,-.00129,
-.00398,-.00044,
90.*
4,1,15,-.00044,.00398,
-.000208,.003999,
.000025,.004004,
.000258,.003996,
.00044,.00398,
.00129,.00483,
.001007,.004897,
.000721,.004947,
.000432,.004981,
.000141,.004997,
-.000149,.004997,
-.00044,.00498,
-.000729,.004946,
-.001015,.004895,
-.00129,.00483,
-.00044,.00398,
90.*
%
%ADD31MACRO31*%
%AMMACRO28*
4,1,15,-.00398,.00044,
-.003999,.000208,
-.004004,-.000025,
-.003996,-.000258,
-.00398,-.00044,
-.00483,-.00129,
-.004897,-.001007,
-.004947,-.000721,
-.004981,-.000432,
-.004997,-.000141,
-.004997,.000149,
-.00498,.00044,
-.004946,.000729,
-.004895,.001015,
-.00483,.00129,
-.00398,.00044,
90.*
4,1,15,-.00044,-.00398,
-.000208,-.003999,
.000025,-.004004,
.000258,-.003996,
.00044,-.00398,
.00129,-.00483,
.001007,-.004897,
.000721,-.004947,
.000432,-.004981,
.000141,-.004997,
-.000149,-.004997,
-.00044,-.00498,
-.000729,-.004946,
-.001015,-.004895,
-.00129,-.00483,
-.00044,-.00398,
90.*
4,1,15,.00398,-.00044,
.003999,-.000208,
.004004,.000025,
.003996,.000258,
.00398,.00044,
.00483,.00129,
.004897,.001007,
.004947,.000721,
.004981,.000432,
.004997,.000141,
.004997,-.000149,
.00498,-.00044,
.004946,-.000729,
.004895,-.001015,
.00483,-.00129,
.00398,-.00044,
90.*
4,1,15,.00044,.00398,
.000208,.003999,
-.000025,.004004,
-.000258,.003996,
-.00044,.00398,
-.00129,.00483,
-.001007,.004897,
-.000721,.004947,
-.000432,.004981,
-.000141,.004997,
.000149,.004997,
.00044,.00498,
.000729,.004946,
.001015,.004895,
.00129,.00483,
.00044,.00398,
90.*
%
%ADD28MACRO28*%
%AMMACRO11*
4,1,15,.00398,.00044,
.003999,.000208,
.004004,-.000025,
.003996,-.000258,
.00398,-.00044,
.00483,-.00129,
.004897,-.001007,
.004947,-.000721,
.004981,-.000432,
.004997,-.000141,
.004997,.000149,
.00498,.00044,
.004946,.000729,
.004895,.001015,
.00483,.00129,
.00398,.00044,
0.0*
4,1,15,.00044,-.00398,
.000208,-.003999,
-.000025,-.004004,
-.000258,-.003996,
-.00044,-.00398,
-.00129,-.00483,
-.001007,-.004897,
-.000721,-.004947,
-.000432,-.004981,
-.000141,-.004997,
.000149,-.004997,
.00044,-.00498,
.000729,-.004946,
.001015,-.004895,
.00129,-.00483,
.00044,-.00398,
0.0*
4,1,15,-.00398,-.00044,
-.003999,-.000208,
-.004004,.000025,
-.003996,.000258,
-.00398,.00044,
-.00483,.00129,
-.004897,.001007,
-.004947,.000721,
-.004981,.000432,
-.004997,.000141,
-.004997,-.000149,
-.00498,-.00044,
-.004946,-.000729,
-.004895,-.001015,
-.00483,-.00129,
-.00398,-.00044,
0.0*
4,1,15,-.00044,.00398,
-.000208,.003999,
.000025,.004004,
.000258,.003996,
.00044,.00398,
.00129,.00483,
.001007,.004897,
.000721,.004947,
.000432,.004981,
.000141,.004997,
-.000149,.004997,
-.00044,.00498,
-.000729,.004946,
-.001015,.004895,
-.00129,.00483,
-.00044,.00398,
0.0*
%
%ADD11MACRO11*%
%AMMACRO36*
4,1,47,.19499,.0719,
.215281,.036007,
.229031,-.002865,
.235822,-.043533,
.235448,-.084763,
.22792,-.125302,
.213467,-.163917,
.192528,-.199436,
.16574,-.23078,
.133915,-.256995,
.098022,-.277286,
.059151,-.291036,
.018482,-.297827,
-.022748,-.297453,
-.063286,-.289925,
-.101902,-.275472,
-.137421,-.254533,
-.168764,-.227745,
-.19498,-.19592,
-.215271,-.160027,
-.229021,-.121156,
-.235812,-.080487,
-.235438,-.039257,
-.22791,.001281,
-.213457,.039897,
-.19498,.0719,
-.17079,.109417,
-.148822,.148276,
-.129151,.188348,
-.11538,.22052,
-.105587,.239854,
-.092586,.257193,
-.076771,.272012,
-.058623,.283859,
-.038693,.292375,
-.017588,.297301,
.004052,.298487,
.025569,.295897,
.04631,.28961,
.065644,.279817,
.082983,.266816,
.097802,.251001,
.109649,.232853,
.1154,.22052,
.133222,.179593,
.153393,.139771,
.175846,.101189,
.19499,.0719,
0.0*
%
%ADD36MACRO36*%
%AMMACRO23*
4,1,15,-.00398,.00044,
-.003999,.000208,
-.004004,-.000025,
-.003996,-.000258,
-.00398,-.00044,
-.00483,-.00129,
-.004897,-.001007,
-.004947,-.000721,
-.004981,-.000432,
-.004997,-.000141,
-.004997,.000149,
-.00498,.00044,
-.004946,.000729,
-.004895,.001015,
-.00483,.00129,
-.00398,.00044,
0.0*
4,1,15,-.00044,-.00398,
-.000208,-.003999,
.000025,-.004004,
.000258,-.003996,
.00044,-.00398,
.00129,-.00483,
.001007,-.004897,
.000721,-.004947,
.000432,-.004981,
.000141,-.004997,
-.000149,-.004997,
-.00044,-.00498,
-.000729,-.004946,
-.001015,-.004895,
-.00129,-.00483,
-.00044,-.00398,
0.0*
4,1,15,.00398,-.00044,
.003999,-.000208,
.004004,.000025,
.003996,.000258,
.00398,.00044,
.00483,.00129,
.004897,.001007,
.004947,.000721,
.004981,.000432,
.004997,.000141,
.004997,-.000149,
.00498,-.00044,
.004946,-.000729,
.004895,-.001015,
.00483,-.00129,
.00398,-.00044,
0.0*
4,1,15,.00044,.00398,
.000208,.003999,
-.000025,.004004,
-.000258,.003996,
-.00044,.00398,
-.00129,.00483,
-.001007,.004897,
-.000721,.004947,
-.000432,.004981,
-.000141,.004997,
.000149,.004997,
.00044,.00498,
.000729,.004946,
.001015,.004895,
.00129,.00483,
.00044,.00398,
0.0*
%
%ADD23MACRO23*%
%ADD38C,.121*%
%ADD33C,.122*%
%ADD15C,.114*%
%ADD18C,.115*%
%ADD12O,.206X.285*%
%ADD34C,.125*%
%ADD10C,.206*%
%ADD35C,.432*%
%ADD26C,.18*%
%ADD13C,.208*%
%ADD39O,.159X.237*%
%ADD27C,.139*%
%ADD17C,.265*%
%ADD40C,.159*%
%ADD44C,.178*%
%AMMACRO25*
4,1,15,.00398,.00044,
.003999,.000208,
.004004,-.000025,
.003996,-.000258,
.00398,-.00044,
.00483,-.00129,
.004897,-.001007,
.004947,-.000721,
.004981,-.000432,
.004997,-.000141,
.004997,.000149,
.00498,.00044,
.004946,.000729,
.004895,.001015,
.00483,.00129,
.00398,.00044,
270.*
4,1,15,.00044,-.00398,
.000208,-.003999,
-.000025,-.004004,
-.000258,-.003996,
-.00044,-.00398,
-.00129,-.00483,
-.001007,-.004897,
-.000721,-.004947,
-.000432,-.004981,
-.000141,-.004997,
.000149,-.004997,
.00044,-.00498,
.000729,-.004946,
.001015,-.004895,
.00129,-.00483,
.00044,-.00398,
270.*
4,1,15,-.00398,-.00044,
-.003999,-.000208,
-.004004,.000025,
-.003996,.000258,
-.00398,.00044,
-.00483,.00129,
-.004897,.001007,
-.004947,.000721,
-.004981,.000432,
-.004997,.000141,
-.004997,-.000149,
-.00498,-.00044,
-.004946,-.000729,
-.004895,-.001015,
-.00483,-.00129,
-.00398,-.00044,
270.*
4,1,15,-.00044,.00398,
-.000208,.003999,
.000025,.004004,
.000258,.003996,
.00044,.00398,
.00129,.00483,
.001007,.004897,
.000721,.004947,
.000432,.004981,
.000141,.004997,
-.000149,.004997,
-.00044,.00498,
-.000729,.004946,
-.001015,.004895,
-.00129,.00483,
-.00044,.00398,
270.*
%
%ADD25MACRO25*%
%AMMACRO16*
4,1,15,.00398,.00044,
.003999,.000208,
.004004,-.000025,
.003996,-.000258,
.00398,-.00044,
.00483,-.00129,
.004897,-.001007,
.004947,-.000721,
.004981,-.000432,
.004997,-.000141,
.004997,.000149,
.00498,.00044,
.004946,.000729,
.004895,.001015,
.00483,.00129,
.00398,.00044,
180.*
4,1,15,.00044,-.00398,
.000208,-.003999,
-.000025,-.004004,
-.000258,-.003996,
-.00044,-.00398,
-.00129,-.00483,
-.001007,-.004897,
-.000721,-.004947,
-.000432,-.004981,
-.000141,-.004997,
.000149,-.004997,
.00044,-.00498,
.000729,-.004946,
.001015,-.004895,
.00129,-.00483,
.00044,-.00398,
180.*
4,1,15,-.00398,-.00044,
-.003999,-.000208,
-.004004,.000025,
-.003996,.000258,
-.00398,.00044,
-.00483,.00129,
-.004897,.001007,
-.004947,.000721,
-.004981,.000432,
-.004997,.000141,
-.004997,-.000149,
-.00498,-.00044,
-.004946,-.000729,
-.004895,-.001015,
-.00483,-.00129,
-.00398,-.00044,
180.*
4,1,15,-.00044,.00398,
-.000208,.003999,
.000025,.004004,
.000258,.003996,
.00044,.00398,
.00129,.00483,
.001007,.004897,
.000721,.004947,
.000432,.004981,
.000141,.004997,
-.000149,.004997,
-.00044,.00498,
-.000729,.004946,
-.001015,.004895,
-.00129,.00483,
-.00044,.00398,
180.*
%
%ADD16MACRO16*%
%AMMACRO30*
4,1,15,-.00398,.00044,
-.003999,.000208,
-.004004,-.000025,
-.003996,-.000258,
-.00398,-.00044,
-.00483,-.00129,
-.004897,-.001007,
-.004947,-.000721,
-.004981,-.000432,
-.004997,-.000141,
-.004997,.000149,
-.00498,.00044,
-.004946,.000729,
-.004895,.001015,
-.00483,.00129,
-.00398,.00044,
270.*
4,1,15,-.00044,-.00398,
-.000208,-.003999,
.000025,-.004004,
.000258,-.003996,
.00044,-.00398,
.00129,-.00483,
.001007,-.004897,
.000721,-.004947,
.000432,-.004981,
.000141,-.004997,
-.000149,-.004997,
-.00044,-.00498,
-.000729,-.004946,
-.001015,-.004895,
-.00129,-.00483,
-.00044,-.00398,
270.*
4,1,15,.00398,-.00044,
.003999,-.000208,
.004004,.000025,
.003996,.000258,
.00398,.00044,
.00483,.00129,
.004897,.001007,
.004947,.000721,
.004981,.000432,
.004997,.000141,
.004997,-.000149,
.00498,-.00044,
.004946,-.000729,
.004895,-.001015,
.00483,-.00129,
.00398,-.00044,
270.*
4,1,15,.00044,.00398,
.000208,.003999,
-.000025,.004004,
-.000258,.003996,
-.00044,.00398,
-.00129,.00483,
-.001007,.004897,
-.000721,.004947,
-.000432,.004981,
-.000141,.004997,
.000149,.004997,
.00044,.00498,
.000729,.004946,
.001015,.004895,
.00129,.00483,
.00044,.00398,
270.*
%
%ADD30MACRO30*%
%AMMACRO29*
4,1,15,-.00398,.00044,
-.003999,.000208,
-.004004,-.000025,
-.003996,-.000258,
-.00398,-.00044,
-.00483,-.00129,
-.004897,-.001007,
-.004947,-.000721,
-.004981,-.000432,
-.004997,-.000141,
-.004997,.000149,
-.00498,.00044,
-.004946,.000729,
-.004895,.001015,
-.00483,.00129,
-.00398,.00044,
180.*
4,1,15,-.00044,-.00398,
-.000208,-.003999,
.000025,-.004004,
.000258,-.003996,
.00044,-.00398,
.00129,-.00483,
.001007,-.004897,
.000721,-.004947,
.000432,-.004981,
.000141,-.004997,
-.000149,-.004997,
-.00044,-.00498,
-.000729,-.004946,
-.001015,-.004895,
-.00129,-.00483,
-.00044,-.00398,
180.*
4,1,15,.00398,-.00044,
.003999,-.000208,
.004004,.000025,
.003996,.000258,
.00398,.00044,
.00483,.00129,
.004897,.001007,
.004947,.000721,
.004981,.000432,
.004997,.000141,
.004997,-.000149,
.00498,-.00044,
.004946,-.000729,
.004895,-.001015,
.00483,-.00129,
.00398,-.00044,
180.*
4,1,15,.00044,.00398,
.000208,.003999,
-.000025,.004004,
-.000258,.003996,
-.00044,.00398,
-.00129,.00483,
-.001007,.004897,
-.000721,.004947,
-.000432,.004981,
-.000141,.004997,
.000149,.004997,
.00044,.00498,
.000729,.004946,
.001015,.004895,
.00129,.00483,
.00044,.00398,
180.*
%
%ADD29MACRO29*%
%ADD45C,.02*%
%ADD46C,.006*%
%ADD56C,.06104*%
%ADD57C,.07704*%
%ADD58C,.11004*%
%ADD55C,.11104*%
%ADD62C,.11704*%
%ADD59C,.13504*%
%ADD61C,.11804*%
%ADD54C,.37504*%
%ADD64C,.29531*%
%ADD53C,.29532*%
%ADD63C,.29533*%
%ADD60C,.23629*%
%ADD47O,.55202X.78802*%
%ADD50O,.09834X.04322*%
%ADD48O,.55204X.78804*%
%ADD52O,.09854X.04342*%
%ADD49O,.09836X.04324*%
%ADD51O,.09856X.04344*%
G75*
%LPD*%
G75*
G36*
G01X-6000Y-158756D02*
X1940843D01*
Y1664268D01*
X-6000D01*
Y-158756D01*
G37*
%LPC*%
G75*
G36*
G01X1216535Y1655264D02*
G02X1217468Y1654331I0J-933D01*
G01Y1476378D01*
G02X1216535Y1475445I-933J0D01*
G01X1168110D01*
G03X1161169Y1468504I0J-6941D01*
G01Y1378740D01*
G03X1168110Y1371799I6941J0D01*
G01X1930906D01*
G02X1931839Y1370866I0J-933D01*
G01Y3937D01*
G02X1930906Y3004I-933J0D01*
G01X1562992D01*
G02X1562059Y3937I0J933D01*
G01Y55118D01*
G03X1555118Y62059I-6941J0D01*
G01X1374016D01*
G03X1367075Y55118I0J-6941D01*
G01Y3937D01*
G02X1366142Y3004I-933J0D01*
G01X1185039D01*
G03X1178098Y-3937I0J-6941D01*
G01Y-148819D01*
G02X1177165Y-149752I-933J0D01*
G01X870079D01*
G02X869146Y-148819I0J933D01*
G01Y-11811D01*
G03X862205Y-4870I-6941J0D01*
G01X791339D01*
G02X790406Y-3937I0J933D01*
G03X783465Y3004I-6941J0D01*
G01X594488D01*
G02X593555Y3937I0J933D01*
G01Y55118D01*
G03X586614Y62059I-6941J0D01*
G01X405512D01*
G03X398571Y55118I0J-6941D01*
G01Y3937D01*
G02X397638Y3004I-933J0D01*
G01X3937D01*
G02X3004Y3937I0J933D01*
G01Y12071D01*
G02X3714Y12323I400J0D01*
G03X29922Y21653I11443J9331D01*
G01Y21654D01*
G03X3714Y30984I-14765J0D01*
G02X3004Y31236I-310J253D01*
G01Y464768D01*
G02X3713Y465022I400J0D01*
G03X12310Y459884I11444J9387D01*
G03X18004I2847J10575D01*
G03Y488934I-2847J14525D01*
G03X12310I-2847J-10575D01*
G03X3713Y483796I2847J-14525D01*
G02X3004Y484050I-309J254D01*
G01Y1370866D01*
G02X3937Y1371799I933J0D01*
G01X746850D01*
G03X753791Y1378740I0J6941D01*
G01Y1464567D01*
G02X754724Y1465500I933J0D01*
G01X783465D01*
G03X790406Y1472441I0J6941D01*
G01Y1654331D01*
G02X791339Y1655264I933J0D01*
G01X1216535D01*
G37*
%LPD*%
G75*
G36*
G01X1124313Y534842D02*
X1124318Y534833D01*
X1116440Y530894D01*
X1116437Y530899D01*
X1116339Y530857D01*
G02X1113786Y535977I-1183J2607D01*
G01X1113872Y536027D01*
X1113870Y536032D01*
X1121747Y539971D01*
X1121753Y539965D01*
X1121814Y539992D01*
G02X1124313Y534842I1217J-2591D01*
G37*
G36*
G01X956203D02*
X956208Y534833D01*
X948330Y530894D01*
X948327Y530899D01*
X948229Y530857D01*
G02X945676Y535977I-1183J2607D01*
G01X945762Y536027D01*
X945760Y536032D01*
X953637Y539971D01*
X953643Y539965D01*
X953704Y539992D01*
G02X956203Y534842I1217J-2591D01*
G37*
G36*
G01X1897508Y459879D02*
G02X1891860I-2824J10580D01*
G02Y488939I2824J14530D01*
G02X1897508I2824J-10580D01*
G02Y459879I-2824J-14530D01*
G37*
G36*
G01X956203Y424606D02*
X956208Y424597D01*
X948330Y420658D01*
X948327Y420663D01*
X948229Y420621D01*
G02X945676Y425741I-1183J2607D01*
G01X945762Y425791D01*
X945760Y425796D01*
X953637Y429735D01*
X953643Y429729D01*
X953704Y429756D01*
G02X956203Y424606I1217J-2591D01*
G37*
G36*
G01X907745Y-40121D02*
G02X902097I-2824J10580D01*
G02Y-11061I2824J14530D01*
G02X907745I2824J-10580D01*
G02Y-40121I-2824J-14530D01*
G37*
G36*
G01X1535036Y77756D02*
Y72244D01*
G02X1530712Y72245I-2162J1D01*
G01Y77756D01*
G02X1535036I2162J0D01*
G37*
G36*
G01Y91930D02*
Y86417D01*
G02X1530712Y86418I-2162J1D01*
G01Y91930D01*
G02X1535036I2162J0D01*
G37*
G36*
G01X1527948Y87993D02*
Y82480D01*
G02X1523626Y82481I-2161J1D01*
G01Y87993D01*
G02X1527948I2161J0D01*
G37*
G36*
G01X1535036Y120276D02*
Y114763D01*
G02X1530712Y114764I-2162J1D01*
G01Y120276D01*
G02X1535036I2162J0D01*
G37*
G36*
G01X1527948Y73819D02*
Y68306D01*
G02X1523626Y68307I-2161J1D01*
G01Y73819D01*
G02X1527948I2161J0D01*
G37*
G36*
G01X1520862Y77756D02*
Y72244D01*
G02X1516540Y72245I-2161J1D01*
G01Y77756D01*
G02X1520862I2161J0D01*
G37*
G36*
G01X1506690D02*
Y72244D01*
G02X1502366Y72245I-2162J1D01*
G01Y77756D01*
G02X1506690I2162J0D01*
G37*
G36*
G01X1492516D02*
Y72244D01*
G02X1488192Y72245I-2162J1D01*
G01Y77756D01*
G02X1492516I2162J0D01*
G37*
G36*
G01X1520862Y91930D02*
Y86417D01*
G02X1516540Y86418I-2161J1D01*
G01Y91930D01*
G02X1520862I2161J0D01*
G37*
G36*
G01X1513776Y87993D02*
Y82480D01*
G02X1509452Y82481I-2162J1D01*
G01Y87993D01*
G02X1513776I2162J0D01*
G37*
G36*
G01X1506690Y91930D02*
Y86417D01*
G02X1502366Y86418I-2162J1D01*
G01Y91930D01*
G02X1506690I2162J0D01*
G37*
G36*
G01X1499602Y87993D02*
Y82480D01*
G02X1495280Y82481I-2161J1D01*
G01Y87993D01*
G02X1499602I2161J0D01*
G37*
G36*
G01X1492516Y91930D02*
Y86417D01*
G02X1488192Y86418I-2162J1D01*
G01Y91930D01*
G02X1492516I2162J0D01*
G37*
G36*
G01X1485430Y87993D02*
Y82480D01*
G02X1481106Y82481I-2162J1D01*
G01Y87993D01*
G02X1485430I2162J0D01*
G37*
G36*
G01X1506700Y120276D02*
Y114763D01*
G02X1502356Y114764I-2172J1D01*
G01Y120276D01*
G02X1506700I2172J0D01*
G37*
G36*
G01X1513776Y73819D02*
Y68306D01*
G02X1509452Y68307I-2162J1D01*
G01Y73819D01*
G02X1513776I2162J0D01*
G37*
G36*
G01X1499602D02*
Y68306D01*
G02X1495280Y68307I-2161J1D01*
G01Y73819D01*
G02X1499602I2161J0D01*
G37*
G36*
G01X1485430D02*
Y68306D01*
G02X1481106Y68307I-2162J1D01*
G01Y73819D01*
G02X1485430I2162J0D01*
G37*
G36*
G01X1449996Y77756D02*
Y72244D01*
G02X1445674Y72245I-2161J1D01*
G01Y77756D01*
G02X1449996I2161J0D01*
G37*
G36*
G01X1435822D02*
Y72244D01*
G02X1431500Y72245I-2161J1D01*
G01Y77756D01*
G02X1435822I2161J0D01*
G37*
G36*
G01X1449996Y91930D02*
Y86417D01*
G02X1445674Y86418I-2161J1D01*
G01Y91930D01*
G02X1449996I2161J0D01*
G37*
G36*
G01X1442910Y87993D02*
Y82480D01*
G02X1438586Y82481I-2162J1D01*
G01Y87993D01*
G02X1442910I2162J0D01*
G37*
G36*
G01X1435822Y91930D02*
Y86417D01*
G02X1431500Y86418I-2161J1D01*
G01Y91930D01*
G02X1435822I2161J0D01*
G37*
G36*
G01X1445664Y114764D02*
Y120277D01*
G02X1450006Y120276I2171J-1D01*
G01Y114764D01*
G02X1445664I-2171J0D01*
G37*
G36*
G01X1442910Y73819D02*
Y68306D01*
G02X1438586Y68307I-2162J1D01*
G01Y73819D01*
G02X1442910I2162J0D01*
G37*
G36*
G01X1404234Y190242D02*
Y185741D01*
G02X1401192Y185742I-1521J1D01*
G01Y190242D01*
G02X1404234I1521J0D01*
G37*
G36*
G01X1385463Y166302D02*
X1380962D01*
G02X1380963Y169344I1J1521D01*
G01X1385463D01*
G02Y166302I0J-1521D01*
G37*
G36*
G01X1421650Y77756D02*
Y72244D01*
G02X1417326Y72245I-2162J1D01*
G01Y77756D01*
G02X1421650I2162J0D01*
G37*
G36*
G01X1407476D02*
Y72244D01*
G02X1403154Y72245I-2161J1D01*
G01Y77756D01*
G02X1407476I2161J0D01*
G37*
G36*
G01X1428736Y87993D02*
Y82480D01*
G02X1424414Y82481I-2161J1D01*
G01Y87993D01*
G02X1428736I2161J0D01*
G37*
G36*
G01X1421650Y91930D02*
Y86417D01*
G02X1417326Y86418I-2162J1D01*
G01Y91930D01*
G02X1421650I2162J0D01*
G37*
G36*
G01X1414564Y87993D02*
Y82480D01*
G02X1410240Y82481I-2162J1D01*
G01Y87993D01*
G02X1414564I2162J0D01*
G37*
G36*
G01X1407476Y91930D02*
Y86417D01*
G02X1403154Y86418I-2161J1D01*
G01Y91930D01*
G02X1407476I2161J0D01*
G37*
G36*
G01X1400390Y87993D02*
Y82480D01*
G02X1396066Y82481I-2162J1D01*
G01Y87993D01*
G02X1400390I2162J0D01*
G37*
G36*
G01X1428736Y116339D02*
Y110826D01*
G02X1424414Y110827I-2161J1D01*
G01Y116339D01*
G02X1428736I2161J0D01*
G37*
G36*
G01Y73819D02*
Y68306D01*
G02X1424414Y68307I-2161J1D01*
G01Y73819D01*
G02X1428736I2161J0D01*
G37*
G36*
G01X1414564D02*
Y68306D01*
G02X1410240Y68307I-2162J1D01*
G01Y73819D01*
G02X1414564I2162J0D01*
G37*
G36*
G01X1400390D02*
Y68306D01*
G02X1396066Y68307I-2162J1D01*
G01Y73819D01*
G02X1400390I2162J0D01*
G37*
G36*
G01X1261462Y1080754D02*
Y1076253D01*
G02X1258138Y1076254I-1662J1D01*
G01Y1080754D01*
G02X1261462I1662J0D01*
G37*
G36*
G01X1113922Y709162D02*
X1121763Y713082D01*
X1121764Y713083D01*
G02X1124266Y708159I1267J-2454D01*
G01X1116392Y704222D01*
G02X1113922Y709162I-1235J2470D01*
G37*
G36*
G01X1104199Y696183D02*
X1104034Y696253D01*
X1104032Y696249D01*
X1096156Y700187D01*
Y700195D01*
X1096053Y700252D01*
G02X1098557Y705390I1388J2503D01*
G01X1098722Y705320D01*
X1098724Y705324D01*
X1106601Y701386D01*
X1106599Y701382D01*
X1106767Y701283D01*
G02X1104199Y696183I-1453J-2465D01*
G37*
G36*
G01X1113922Y693414D02*
X1121763Y697334D01*
X1121764Y697335D01*
G02X1124266Y692411I1267J-2454D01*
G01X1116392Y688474D01*
G02X1113922Y693414I-1235J2470D01*
G37*
G36*
G01Y677666D02*
X1121763Y681586D01*
X1121764Y681587D01*
G02X1124266Y676663I1267J-2454D01*
G01X1116392Y672726D01*
G02X1113922Y677666I-1235J2470D01*
G37*
G36*
G01Y661918D02*
X1121763Y665838D01*
X1121764Y665839D01*
G02X1124266Y660915I1267J-2454D01*
G01X1116392Y656978D01*
G02X1113922Y661918I-1235J2470D01*
G37*
G36*
G01X1104199Y680435D02*
X1104034Y680505D01*
X1104032Y680501D01*
X1096156Y684439D01*
Y684447D01*
X1096053Y684504D01*
G02X1098557Y689642I1388J2503D01*
G01X1098722Y689572D01*
X1098724Y689576D01*
X1106601Y685638D01*
X1106599Y685634D01*
X1106767Y685535D01*
G02X1104199Y680435I-1453J-2465D01*
G37*
G36*
G01Y664687D02*
X1104034Y664757D01*
X1104032Y664753D01*
X1096156Y668691D01*
Y668699D01*
X1096053Y668756D01*
G02X1098557Y673894I1388J2503D01*
G01X1098722Y673824D01*
X1098724Y673828D01*
X1106601Y669890D01*
X1106599Y669886D01*
X1106767Y669787D01*
G02X1104199Y664687I-1453J-2465D01*
G37*
G36*
G01Y648939D02*
X1104034Y649009D01*
X1104032Y649005D01*
X1096156Y652943D01*
Y652951D01*
X1096053Y653008D01*
G02X1098557Y658146I1388J2503D01*
G01X1098722Y658076D01*
X1098724Y658080D01*
X1106601Y654142D01*
X1106599Y654138D01*
X1106767Y654039D01*
G02X1104199Y648939I-1453J-2465D01*
G37*
G36*
G01X1113922Y646170D02*
X1121763Y650090D01*
X1121764Y650091D01*
G02X1124266Y645167I1267J-2454D01*
G01X1116392Y641230D01*
G02X1113922Y646170I-1235J2470D01*
G37*
G36*
G01X1124266Y629419D02*
X1116425Y625499D01*
X1116424Y625498D01*
G02X1113922Y630422I-1267J2454D01*
G01X1121796Y634359D01*
G02X1124266Y629419I1235J-2470D01*
G37*
G36*
G01X1113922Y614674D02*
X1121763Y618594D01*
X1121764Y618595D01*
G02X1124266Y613671I1267J-2454D01*
G01X1116392Y609734D01*
G02X1113922Y614674I-1235J2470D01*
G37*
G36*
G01X1104039Y601780D02*
X1096133Y605733D01*
X1096062Y605771D01*
G02X1098717Y610817I1379J2496D01*
G01X1106591Y606880D01*
G02X1104039Y601780I-1276J-2550D01*
G37*
G36*
G01Y617528D02*
X1096133Y621481D01*
X1096062Y621519D01*
G02X1098717Y626565I1379J2496D01*
G01X1106591Y622628D01*
G02X1104039Y617528I-1276J-2550D01*
G37*
G36*
G01Y633276D02*
X1096133Y637229D01*
X1096062Y637267D01*
G02X1098717Y642313I1379J2496D01*
G01X1106591Y638376D01*
G02X1104039Y633276I-1276J-2550D01*
G37*
G36*
G01X1113922Y598926D02*
X1121763Y602846D01*
X1121764Y602847D01*
G02X1124266Y597923I1267J-2454D01*
G01X1116392Y593986D01*
G02X1113922Y598926I-1235J2470D01*
G37*
G36*
G01X1104039Y586032D02*
X1096133Y589985D01*
X1096062Y590023D01*
G02X1098717Y595069I1379J2496D01*
G01X1106591Y591132D01*
G02X1104039Y586032I-1276J-2550D01*
G37*
G36*
G01Y507292D02*
X1096133Y511245D01*
X1096062Y511283D01*
G02X1098717Y516329I1379J2496D01*
G01X1106591Y512392D01*
G02X1104039Y507292I-1276J-2550D01*
G37*
G36*
G01X1104199Y538703D02*
X1104034Y538773D01*
X1104032Y538769D01*
X1096156Y542707D01*
Y542715D01*
X1096053Y542772D01*
G02X1098557Y547910I1388J2503D01*
G01X1098722Y547840D01*
X1098724Y547844D01*
X1106601Y543906D01*
X1106599Y543902D01*
X1106767Y543803D01*
G02X1104199Y538703I-1453J-2465D01*
G37*
G36*
G01X1113922Y504438D02*
X1121763Y508358D01*
X1121764Y508359D01*
G02X1124266Y503435I1267J-2454D01*
G01X1116392Y499498D01*
G02X1113922Y504438I-1235J2470D01*
G37*
G36*
G01Y488690D02*
X1121763Y492610D01*
X1121764Y492611D01*
G02X1124266Y487687I1267J-2454D01*
G01X1116392Y483750D01*
G02X1113922Y488690I-1235J2470D01*
G37*
G36*
G01Y472942D02*
X1121763Y476862D01*
X1121764Y476863D01*
G02X1124266Y471939I1267J-2454D01*
G01X1116392Y468002D01*
G02X1113922Y472942I-1235J2470D01*
G37*
G36*
G01X1104039Y460048D02*
X1096133Y464001D01*
X1096062Y464039D01*
G02X1098717Y469085I1379J2496D01*
G01X1106591Y465148D01*
G02X1104039Y460048I-1276J-2550D01*
G37*
G36*
G01Y475796D02*
X1096133Y479749D01*
X1096062Y479787D01*
G02X1098717Y484833I1379J2496D01*
G01X1106591Y480896D01*
G02X1104039Y475796I-1276J-2550D01*
G37*
G36*
G01Y491544D02*
X1096133Y495497D01*
X1096062Y495535D01*
G02X1098717Y500581I1379J2496D01*
G01X1106591Y496644D01*
G02X1104039Y491544I-1276J-2550D01*
G37*
G36*
G01X1098676Y453257D02*
X1106550Y449320D01*
G02X1104080Y444380I-1235J-2470D01*
G01X1096239Y448301D01*
X1096238D01*
G02X1098676Y453257I1203J2486D01*
G37*
G36*
G01X1113922Y457194D02*
X1121763Y461114D01*
X1121764Y461115D01*
G02X1124266Y456191I1267J-2454D01*
G01X1116392Y452254D01*
G02X1113922Y457194I-1235J2470D01*
G37*
G36*
G01X1113872Y425796D02*
X1121746Y429733D01*
G02X1124316Y424597I1285J-2568D01*
G01X1116442Y420660D01*
G02X1113872Y425796I-1285J2568D01*
G37*
G36*
G01X1113922Y330029D02*
X1121763Y333949D01*
X1121764Y333950D01*
G02X1124266Y329026I1267J-2454D01*
G01X1116392Y325089D01*
G02X1113922Y330029I-1235J2470D01*
G37*
G36*
G01X1104199Y317050D02*
X1104034Y317120D01*
X1104032Y317116D01*
X1096156Y321054D01*
Y321062D01*
X1096053Y321119D01*
G02X1098557Y326257I1388J2503D01*
G01X1098722Y326187D01*
X1098724Y326191D01*
X1106601Y322253D01*
X1106599Y322249D01*
X1106767Y322150D01*
G02X1104199Y317050I-1453J-2465D01*
G37*
G36*
G01X1113922Y314281D02*
X1121763Y318201D01*
X1121764Y318202D01*
G02X1124266Y313278I1267J-2454D01*
G01X1116392Y309341D01*
G02X1113922Y314281I-1235J2470D01*
G37*
G36*
G01Y282785D02*
X1121763Y286705D01*
X1121764Y286706D01*
G02X1124266Y281782I1267J-2454D01*
G01X1116392Y277845D01*
G02X1113922Y282785I-1235J2470D01*
G37*
G36*
G01Y267037D02*
X1121763Y270957D01*
X1121764Y270958D01*
G02X1124266Y266034I1267J-2454D01*
G01X1116392Y262097D01*
G02X1113922Y267037I-1235J2470D01*
G37*
G36*
G01X1104199Y269806D02*
X1104034Y269876D01*
X1104032Y269872D01*
X1096156Y273810D01*
Y273818D01*
X1096053Y273875D01*
G02X1098557Y279013I1388J2503D01*
G01X1098722Y278943D01*
X1098724Y278947D01*
X1106601Y275009D01*
X1106599Y275005D01*
X1106767Y274906D01*
G02X1104199Y269806I-1453J-2465D01*
G37*
G36*
G01Y301302D02*
X1104034Y301372D01*
X1104032Y301368D01*
X1096156Y305306D01*
Y305314D01*
X1096053Y305371D01*
G02X1098557Y310509I1388J2503D01*
G01X1098722Y310439D01*
X1098724Y310443D01*
X1106601Y306505D01*
X1106599Y306501D01*
X1106767Y306402D01*
G02X1104199Y301302I-1453J-2465D01*
G37*
G36*
G01Y285554D02*
X1104034Y285624D01*
X1104032Y285620D01*
X1096156Y289558D01*
Y289566D01*
X1096053Y289623D01*
G02X1098557Y294761I1388J2503D01*
G01X1098722Y294691D01*
X1098724Y294695D01*
X1106601Y290757D01*
X1106599Y290753D01*
X1106767Y290654D01*
G02X1104199Y285554I-1453J-2465D01*
G37*
G36*
G01X1113922Y298533D02*
X1121763Y302453D01*
X1121764Y302454D01*
G02X1124266Y297530I1267J-2454D01*
G01X1116392Y293593D01*
G02X1113922Y298533I-1235J2470D01*
G37*
G36*
G01Y219793D02*
X1121763Y223713D01*
X1121764Y223714D01*
G02X1124266Y218790I1267J-2454D01*
G01X1116392Y214853D01*
G02X1113922Y219793I-1235J2470D01*
G37*
G36*
G01Y235541D02*
X1121763Y239461D01*
X1121764Y239462D01*
G02X1124266Y234538I1267J-2454D01*
G01X1116392Y230601D01*
G02X1113922Y235541I-1235J2470D01*
G37*
G36*
G01X1104199Y222562D02*
X1104034Y222632D01*
X1104032Y222628D01*
X1096156Y226566D01*
Y226574D01*
X1096053Y226631D01*
G02X1098557Y231769I1388J2503D01*
G01X1098722Y231699D01*
X1098724Y231703D01*
X1106601Y227765D01*
X1106599Y227761D01*
X1106767Y227662D01*
G02X1104199Y222562I-1453J-2465D01*
G37*
G36*
G01X1113922Y251289D02*
X1121763Y255209D01*
X1121764Y255210D01*
G02X1124266Y250286I1267J-2454D01*
G01X1116392Y246349D01*
G02X1113922Y251289I-1235J2470D01*
G37*
G36*
G01X1104199Y254058D02*
X1104034Y254128D01*
X1104032Y254124D01*
X1096156Y258062D01*
Y258070D01*
X1096053Y258127D01*
G02X1098557Y263265I1388J2503D01*
G01X1098722Y263195D01*
X1098724Y263199D01*
X1106601Y259261D01*
X1106599Y259257D01*
X1106767Y259158D01*
G02X1104199Y254058I-1453J-2465D01*
G37*
G36*
G01Y238310D02*
X1104034Y238380D01*
X1104032Y238376D01*
X1096156Y242314D01*
Y242322D01*
X1096053Y242379D01*
G02X1098557Y247517I1388J2503D01*
G01X1098722Y247447D01*
X1098724Y247451D01*
X1106601Y243513D01*
X1106599Y243509D01*
X1106767Y243410D01*
G02X1104199Y238310I-1453J-2465D01*
G37*
G36*
G01X1113922Y172549D02*
X1121763Y176469D01*
X1121764Y176470D01*
G02X1124266Y171546I1267J-2454D01*
G01X1116392Y167609D01*
G02X1113922Y172549I-1235J2470D01*
G37*
G36*
G01Y188297D02*
X1121763Y192217D01*
X1121764Y192218D01*
G02X1124266Y187294I1267J-2454D01*
G01X1116392Y183357D01*
G02X1113922Y188297I-1235J2470D01*
G37*
G36*
G01X1104199Y175318D02*
X1104034Y175388D01*
X1104032Y175384D01*
X1096156Y179322D01*
Y179330D01*
X1096053Y179387D01*
G02X1098557Y184525I1388J2503D01*
G01X1098722Y184455D01*
X1098724Y184459D01*
X1106601Y180521D01*
X1106599Y180517D01*
X1106767Y180418D01*
G02X1104199Y175318I-1453J-2465D01*
G37*
G36*
G01Y206814D02*
X1104034Y206884D01*
X1104032Y206880D01*
X1096156Y210818D01*
Y210826D01*
X1096053Y210883D01*
G02X1098557Y216021I1388J2503D01*
G01X1098722Y215951D01*
X1098724Y215955D01*
X1106601Y212017D01*
X1106599Y212013D01*
X1106767Y211914D01*
G02X1104199Y206814I-1453J-2465D01*
G37*
G36*
G01X1113922Y204045D02*
X1121763Y207965D01*
X1121764Y207966D01*
G02X1124266Y203042I1267J-2454D01*
G01X1116392Y199105D01*
G02X1113922Y204045I-1235J2470D01*
G37*
G36*
G01X1104199Y191066D02*
X1104034Y191136D01*
X1104032Y191132D01*
X1096156Y195070D01*
Y195078D01*
X1096053Y195135D01*
G02X1098557Y200273I1388J2503D01*
G01X1098722Y200203D01*
X1098724Y200207D01*
X1106601Y196269D01*
X1106599Y196265D01*
X1106767Y196166D01*
G02X1104199Y191066I-1453J-2465D01*
G37*
G36*
G01X1124320Y139943D02*
X1116446Y136006D01*
G02X1113868Y141160I-1289J2577D01*
G01X1121741Y145097D01*
G02X1124320Y139943I1290J-2577D01*
G37*
G36*
G01X1113922Y156801D02*
X1121763Y160721D01*
X1121764Y160722D01*
G02X1124266Y155798I1267J-2454D01*
G01X1116392Y151861D01*
G02X1113922Y156801I-1235J2470D01*
G37*
G36*
G01X1104199Y143822D02*
X1104034Y143892D01*
X1104032Y143888D01*
X1096156Y147826D01*
Y147834D01*
X1096053Y147891D01*
G02X1098557Y153029I1388J2503D01*
G01X1098722Y152959D01*
X1098724Y152963D01*
X1106601Y149025D01*
X1106599Y149021D01*
X1106767Y148922D01*
G02X1104199Y143822I-1453J-2465D01*
G37*
G36*
G01Y159570D02*
X1104034Y159640D01*
X1104032Y159636D01*
X1096156Y163574D01*
Y163582D01*
X1096053Y163639D01*
G02X1098557Y168777I1388J2503D01*
G01X1098722Y168707D01*
X1098724Y168711D01*
X1106601Y164773D01*
X1106599Y164769D01*
X1106767Y164670D01*
G02X1104199Y159570I-1453J-2465D01*
G37*
G36*
G01X1098730Y50609D02*
X1106604Y46672D01*
G02X1104026Y41518I-1289J-2577D01*
G01X1096195Y45434D01*
X1096194D01*
G02X1098730Y50609I1248J2597D01*
G37*
G36*
G01X1104199Y65082D02*
X1104034Y65152D01*
X1104032Y65148D01*
X1096156Y69086D01*
Y69094D01*
X1096053Y69151D01*
G02X1098557Y74289I1388J2503D01*
G01X1098722Y74219D01*
X1098724Y74223D01*
X1106601Y70285D01*
X1106599Y70281D01*
X1106767Y70182D01*
G02X1104199Y65082I-1453J-2465D01*
G37*
G36*
G01X1075250Y1413872D02*
X1070749D01*
G02X1070750Y1416876I1J1502D01*
G01X1075250D01*
G02Y1413872I0J-1502D01*
G37*
G36*
G01Y1406786D02*
X1070749D01*
G02X1070750Y1409788I1J1501D01*
G01X1075250D01*
G02Y1406786I0J-1501D01*
G37*
G36*
G01Y1399700D02*
X1070749D01*
G02X1070750Y1402702I1J1501D01*
G01X1075250D01*
G02Y1399700I0J-1501D01*
G37*
G36*
G01Y1392612D02*
X1070749D01*
G02X1070750Y1395616I1J1502D01*
G01X1075250D01*
G02Y1392612I0J-1502D01*
G37*
G36*
G01Y1385526D02*
X1070749D01*
G02X1070750Y1388530I1J1502D01*
G01X1075250D01*
G02Y1385526I0J-1502D01*
G37*
G36*
G01Y1378440D02*
X1070749D01*
G02X1070750Y1381442I1J1501D01*
G01X1075250D01*
G02Y1378440I0J-1501D01*
G37*
G36*
G01Y1328824D02*
X1070749D01*
G02X1070750Y1331846I1J1511D01*
G01X1075250D01*
G02Y1328824I0J-1511D01*
G37*
G36*
G01Y1293390D02*
X1070749D01*
G02X1070750Y1296414I1J1512D01*
G01X1075250D01*
G02Y1293390I0J-1512D01*
G37*
G36*
G01Y1300476D02*
X1070749D01*
G02X1070750Y1303500I1J1512D01*
G01X1075250D01*
G02Y1300476I0J-1512D01*
G37*
G36*
G01Y1307564D02*
X1070749D01*
G02X1070750Y1310586I1J1511D01*
G01X1075250D01*
G02Y1307564I0J-1511D01*
G37*
G36*
G01Y1314650D02*
X1070749D01*
G02X1070750Y1317672I1J1511D01*
G01X1075250D01*
G02Y1314650I0J-1511D01*
G37*
G36*
G01Y1321736D02*
X1070749D01*
G02X1070750Y1324760I1J1512D01*
G01X1075250D01*
G02Y1321736I0J-1512D01*
G37*
G36*
G01Y1229610D02*
X1070749D01*
G02X1070750Y1232634I1J1512D01*
G01X1075250D01*
G02Y1229610I0J-1512D01*
G37*
G36*
G01Y1236698D02*
X1070749D01*
G02X1070750Y1239720I1J1511D01*
G01X1075250D01*
G02Y1236698I0J-1511D01*
G37*
G36*
G01Y1243784D02*
X1070749D01*
G02X1070750Y1246806I1J1511D01*
G01X1075250D01*
G02Y1243784I0J-1511D01*
G37*
G36*
G01Y1208350D02*
X1070749D01*
G02X1070750Y1211374I1J1512D01*
G01X1075250D01*
G02Y1208350I0J-1512D01*
G37*
G36*
G01Y1215438D02*
X1070749D01*
G02X1070750Y1218460I1J1511D01*
G01X1075250D01*
G02Y1215438I0J-1511D01*
G37*
G36*
G01Y1222524D02*
X1070749D01*
G02X1070750Y1225546I1J1511D01*
G01X1075250D01*
G02Y1222524I0J-1511D01*
G37*
G36*
G01X956156Y708159D02*
X948315Y704239D01*
X948314Y704238D01*
G02X945812Y709162I-1267J2454D01*
G01X953686Y713099D01*
G02X956156Y708159I1235J-2470D01*
G37*
G36*
G01Y660915D02*
X948315Y656995D01*
X948314Y656994D01*
G02X945812Y661918I-1267J2454D01*
G01X953686Y665855D01*
G02X956156Y660915I1235J-2470D01*
G37*
G36*
G01Y692411D02*
X948315Y688491D01*
X948314Y688490D01*
G02X945812Y693414I-1267J2454D01*
G01X953686Y697351D01*
G02X956156Y692411I1235J-2470D01*
G37*
G36*
G01Y676663D02*
X948315Y672743D01*
X948314Y672742D01*
G02X945812Y677666I-1267J2454D01*
G01X953686Y681603D01*
G02X956156Y676663I1235J-2470D01*
G37*
G36*
G01X956210Y645060D02*
X948337Y641123D01*
G02X945758Y646277I-1290J2577D01*
G01X953632Y650214D01*
G02X956210Y645060I1289J-2577D01*
G37*
G36*
G01X945758Y630529D02*
X953631Y634466D01*
G02X956210Y629312I1290J-2577D01*
G01X948336Y625375D01*
G02X945758Y630529I-1289J2577D01*
G37*
G36*
G01Y614781D02*
X953631Y618718D01*
G02X956210Y613564I1290J-2577D01*
G01X948336Y609627D01*
G02X945758Y614781I-1289J2577D01*
G37*
G36*
G01X956210Y597816D02*
X948337Y593879D01*
G02X945758Y599033I-1290J2577D01*
G01X953632Y602970D01*
G02X956210Y597816I1289J-2577D01*
G37*
G36*
G01X956223Y503301D02*
X948392Y499386D01*
G02X945745Y504572I-1345J2582D01*
G01X953619Y508509D01*
G02X956223Y503301I1302J-2604D01*
G37*
G36*
G01X945745Y488824D02*
X953576Y492739D01*
G02X956223Y487553I1345J-2582D01*
G01X948349Y483616D01*
G02X945745Y488824I-1302J2604D01*
G37*
G36*
G01X945758Y473049D02*
X953631Y476986D01*
G02X956210Y471832I1290J-2577D01*
G01X948336Y467895D01*
G02X945758Y473049I-1289J2577D01*
G37*
G36*
G01X956210Y456084D02*
X948337Y452147D01*
G02X945758Y457301I-1290J2577D01*
G01X953632Y461238D01*
G02X956210Y456084I1289J-2577D01*
G37*
G36*
G01X945812Y314281D02*
X953653Y318201D01*
X953654Y318202D01*
G02X956156Y313278I1267J-2454D01*
G01X948282Y309341D01*
G02X945812Y314281I-1235J2470D01*
G37*
G36*
G01X956156Y329026D02*
X948315Y325106D01*
X948314Y325105D01*
G02X945812Y330029I-1267J2454D01*
G01X953686Y333966D01*
G02X956156Y329026I1235J-2470D01*
G37*
G36*
G01Y266034D02*
X948315Y262114D01*
X948314Y262113D01*
G02X945812Y267037I-1267J2454D01*
G01X953686Y270974D01*
G02X956156Y266034I1235J-2470D01*
G37*
G36*
G01X945812Y282785D02*
X953653Y286705D01*
X953654Y286706D01*
G02X956156Y281782I1267J-2454D01*
G01X948282Y277845D01*
G02X945812Y282785I-1235J2470D01*
G37*
G36*
G01Y298533D02*
X953653Y302453D01*
X953654Y302454D01*
G02X956156Y297530I1267J-2454D01*
G01X948282Y293593D01*
G02X945812Y298533I-1235J2470D01*
G37*
G36*
G01X956156Y218790D02*
X948315Y214870D01*
X948314Y214869D01*
G02X945812Y219793I-1267J2454D01*
G01X953686Y223730D01*
G02X956156Y218790I1235J-2470D01*
G37*
G36*
G01Y234538D02*
X948315Y230618D01*
X948314Y230617D01*
G02X945812Y235541I-1267J2454D01*
G01X953686Y239478D01*
G02X956156Y234538I1235J-2470D01*
G37*
G36*
G01Y250286D02*
X948315Y246366D01*
X948314Y246365D01*
G02X945812Y251289I-1267J2454D01*
G01X953686Y255226D01*
G02X956156Y250286I1235J-2470D01*
G37*
G36*
G01Y171546D02*
X948315Y167626D01*
X948314Y167625D01*
G02X945812Y172549I-1267J2454D01*
G01X953686Y176486D01*
G02X956156Y171546I1235J-2470D01*
G37*
G36*
G01Y187294D02*
X948315Y183374D01*
X948314Y183373D01*
G02X945812Y188297I-1267J2454D01*
G01X953686Y192234D01*
G02X956156Y187294I1235J-2470D01*
G37*
G36*
G01X945812Y204045D02*
X953653Y207965D01*
X953654Y207966D01*
G02X956156Y203042I1267J-2454D01*
G01X948282Y199105D01*
G02X945812Y204045I-1235J2470D01*
G37*
G36*
G01X945762Y141151D02*
X953636Y145088D01*
G02X956206Y139952I1285J-2568D01*
G01X948332Y136015D01*
G02X945762Y141151I-1285J2568D01*
G37*
G36*
G01X956156Y155798D02*
X948315Y151878D01*
X948314Y151877D01*
G02X945812Y156801I-1267J2454D01*
G01X953686Y160738D01*
G02X956156Y155798I1235J-2470D01*
G37*
G36*
G01X936089Y696183D02*
X935924Y696253D01*
X935922Y696249D01*
X928046Y700187D01*
Y700195D01*
X927943Y700252D01*
G02X930447Y705390I1388J2503D01*
G01X930612Y705320D01*
X930614Y705324D01*
X938491Y701386D01*
X938489Y701382D01*
X938657Y701283D01*
G02X936089Y696183I-1453J-2465D01*
G37*
G36*
G01Y680435D02*
X935924Y680505D01*
X935922Y680501D01*
X928046Y684439D01*
Y684447D01*
X927943Y684504D01*
G02X930447Y689642I1388J2503D01*
G01X930612Y689572D01*
X930614Y689576D01*
X938491Y685638D01*
X938489Y685634D01*
X938657Y685535D01*
G02X936089Y680435I-1453J-2465D01*
G37*
G36*
G01Y664687D02*
X935924Y664757D01*
X935922Y664753D01*
X928046Y668691D01*
Y668699D01*
X927943Y668756D01*
G02X930447Y673894I1388J2503D01*
G01X930612Y673824D01*
X930614Y673828D01*
X938491Y669890D01*
X938489Y669886D01*
X938657Y669787D01*
G02X936089Y664687I-1453J-2465D01*
G37*
G36*
G01Y648939D02*
X935924Y649009D01*
X935922Y649005D01*
X928046Y652943D01*
Y652951D01*
X927943Y653008D01*
G02X930447Y658146I1388J2503D01*
G01X930612Y658076D01*
X930614Y658080D01*
X938491Y654142D01*
X938489Y654138D01*
X938657Y654039D01*
G02X936089Y648939I-1453J-2465D01*
G37*
G36*
G01X935916Y601753D02*
X928085Y605669D01*
X928084D01*
G02X930620Y610844I1248J2597D01*
G01X938494Y606907D01*
G02X935916Y601753I-1289J-2577D01*
G37*
G36*
G01Y633249D02*
X928085Y637165D01*
X928084D01*
G02X930620Y642340I1248J2597D01*
G01X938494Y638403D01*
G02X935916Y633249I-1289J-2577D01*
G37*
G36*
G01Y617501D02*
X928085Y621417D01*
X928084D01*
G02X930620Y626592I1248J2597D01*
G01X938494Y622655D01*
G02X935916Y617501I-1289J-2577D01*
G37*
G36*
G01Y586005D02*
X928085Y589921D01*
X928084D01*
G02X930620Y595096I1248J2597D01*
G01X938494Y591159D01*
G02X935916Y586005I-1289J-2577D01*
G37*
G36*
G01Y507265D02*
X928085Y511181D01*
X928084D01*
G02X930620Y516356I1248J2597D01*
G01X938494Y512419D01*
G02X935916Y507265I-1289J-2577D01*
G37*
G36*
G01X936089Y538703D02*
X935924Y538773D01*
X935922Y538769D01*
X928046Y542707D01*
Y542715D01*
X927943Y542772D01*
G02X930447Y547910I1388J2503D01*
G01X930612Y547840D01*
X930614Y547844D01*
X938491Y543906D01*
X938489Y543902D01*
X938657Y543803D01*
G02X936089Y538703I-1453J-2465D01*
G37*
G36*
G01X935916Y491517D02*
X928085Y495433D01*
X928084D01*
G02X930620Y500608I1248J2597D01*
G01X938494Y496671D01*
G02X935916Y491517I-1289J-2577D01*
G37*
G36*
G01X930620Y484860D02*
X938451Y480944D01*
X938452D01*
G02X935916Y475769I-1248J-2597D01*
G01X928042Y479706D01*
G02X930620Y484860I1289J2577D01*
G37*
G36*
G01X935916Y460021D02*
X928085Y463937D01*
X928084D01*
G02X930620Y469112I1248J2597D01*
G01X938494Y465175D01*
G02X935916Y460021I-1289J-2577D01*
G37*
G36*
G01Y444273D02*
X928085Y448189D01*
X928084D01*
G02X930620Y453364I1248J2597D01*
G01X938494Y449427D01*
G02X935916Y444273I-1289J-2577D01*
G37*
G36*
G01X936089Y317050D02*
X935924Y317120D01*
X935922Y317116D01*
X928046Y321054D01*
Y321062D01*
X927943Y321119D01*
G02X930447Y326257I1388J2503D01*
G01X930612Y326187D01*
X930614Y326191D01*
X938491Y322253D01*
X938489Y322249D01*
X938657Y322150D01*
G02X936089Y317050I-1453J-2465D01*
G37*
G36*
G01Y269806D02*
X935924Y269876D01*
X935922Y269872D01*
X928046Y273810D01*
Y273818D01*
X927943Y273875D01*
G02X930447Y279013I1388J2503D01*
G01X930612Y278943D01*
X930614Y278947D01*
X938491Y275009D01*
X938489Y275005D01*
X938657Y274906D01*
G02X936089Y269806I-1453J-2465D01*
G37*
G36*
G01Y301302D02*
X935924Y301372D01*
X935922Y301368D01*
X928046Y305306D01*
Y305314D01*
X927943Y305371D01*
G02X930447Y310509I1388J2503D01*
G01X930612Y310439D01*
X930614Y310443D01*
X938491Y306505D01*
X938489Y306501D01*
X938657Y306402D01*
G02X936089Y301302I-1453J-2465D01*
G37*
G36*
G01Y285554D02*
X935924Y285624D01*
X935922Y285620D01*
X928046Y289558D01*
Y289566D01*
X927943Y289623D01*
G02X930447Y294761I1388J2503D01*
G01X930612Y294691D01*
X930614Y294695D01*
X938491Y290757D01*
X938489Y290753D01*
X938657Y290654D01*
G02X936089Y285554I-1453J-2465D01*
G37*
G36*
G01Y222562D02*
X935924Y222632D01*
X935922Y222628D01*
X928046Y226566D01*
Y226574D01*
X927943Y226631D01*
G02X930447Y231769I1388J2503D01*
G01X930612Y231699D01*
X930614Y231703D01*
X938491Y227765D01*
X938489Y227761D01*
X938657Y227662D01*
G02X936089Y222562I-1453J-2465D01*
G37*
G36*
G01Y254058D02*
X935924Y254128D01*
X935922Y254124D01*
X928045Y258062D01*
X928047Y258066D01*
X927879Y258165D01*
G02X930447Y263265I1453J2465D01*
G01X930612Y263195D01*
X930614Y263199D01*
X938490Y259261D01*
Y259253D01*
X938593Y259196D01*
G02X936089Y254058I-1388J-2503D01*
G37*
G36*
G01Y238310D02*
X935924Y238380D01*
X935922Y238376D01*
X928046Y242314D01*
Y242322D01*
X927943Y242379D01*
G02X930447Y247517I1388J2503D01*
G01X930612Y247447D01*
X930614Y247451D01*
X938491Y243513D01*
X938489Y243509D01*
X938657Y243410D01*
G02X936089Y238310I-1453J-2465D01*
G37*
G36*
G01Y175318D02*
X935924Y175388D01*
X935922Y175384D01*
X928046Y179322D01*
Y179330D01*
X927943Y179387D01*
G02X930447Y184525I1388J2503D01*
G01X930612Y184455D01*
X930614Y184459D01*
X938491Y180521D01*
X938489Y180517D01*
X938657Y180418D01*
G02X936089Y175318I-1453J-2465D01*
G37*
G36*
G01Y191066D02*
X935924Y191136D01*
X935922Y191132D01*
X928046Y195070D01*
Y195078D01*
X927943Y195135D01*
G02X930447Y200273I1388J2503D01*
G01X930612Y200203D01*
X930614Y200207D01*
X938491Y196269D01*
X938489Y196265D01*
X938657Y196166D01*
G02X936089Y191066I-1453J-2465D01*
G37*
G36*
G01Y206814D02*
X935924Y206884D01*
X935922Y206880D01*
X928046Y210818D01*
Y210826D01*
X927943Y210883D01*
G02X930447Y216021I1388J2503D01*
G01X930612Y215951D01*
X930614Y215955D01*
X938491Y212017D01*
X938489Y212013D01*
X938657Y211914D01*
G02X936089Y206814I-1453J-2465D01*
G37*
G36*
G01Y159570D02*
X935924Y159640D01*
X935922Y159636D01*
X928046Y163574D01*
Y163582D01*
X927943Y163639D01*
G02X930447Y168777I1388J2503D01*
G01X930612Y168707D01*
X930614Y168711D01*
X938491Y164773D01*
X938489Y164769D01*
X938657Y164670D01*
G02X936089Y159570I-1453J-2465D01*
G37*
G36*
G01Y143822D02*
X935924Y143892D01*
X935922Y143888D01*
X928046Y147826D01*
Y147834D01*
X927943Y147891D01*
G02X930447Y153029I1388J2503D01*
G01X930612Y152959D01*
X930614Y152963D01*
X938491Y149025D01*
X938489Y149021D01*
X938657Y148922D01*
G02X936089Y143822I-1453J-2465D01*
G37*
G36*
G01X930620Y50609D02*
X938494Y46672D01*
G02X935916Y41518I-1289J-2577D01*
G01X928085Y45434D01*
X928084D01*
G02X930620Y50609I1248J2597D01*
G37*
G36*
G01X936089Y65082D02*
X935924Y65152D01*
X935922Y65148D01*
X928046Y69086D01*
Y69094D01*
X927943Y69151D01*
G02X930447Y74289I1388J2503D01*
G01X930612Y74219D01*
X930614Y74223D01*
X938491Y70285D01*
X938489Y70281D01*
X938657Y70182D01*
G02X936089Y65082I-1453J-2465D01*
G37*
G36*
G01X878540Y1646457D02*
Y1640944D01*
G02X874216Y1640945I-2162J1D01*
G01Y1646457D01*
G02X878540I2162J0D01*
G37*
G36*
G01X871454Y1636221D02*
Y1630708D01*
G02X867130Y1630709I-2162J1D01*
G01Y1636221D01*
G02X871454I2162J0D01*
G37*
G36*
G01X864366Y1646457D02*
Y1640944D01*
G02X860044Y1640945I-2161J1D01*
G01Y1646457D01*
G02X864366I2161J0D01*
G37*
G36*
G01X857280Y1636221D02*
Y1630708D01*
G02X852956Y1630709I-2162J1D01*
G01Y1636221D01*
G02X857280I2162J0D01*
G37*
G36*
G01X850194Y1646457D02*
Y1640944D01*
G02X845870Y1640945I-2162J1D01*
G01Y1646457D01*
G02X850194I2162J0D01*
G37*
G36*
G01X878540Y1603937D02*
Y1598424D01*
G02X874216Y1598425I-2162J1D01*
G01Y1603937D01*
G02X878540I2162J0D01*
G37*
G36*
G01X871454Y1607874D02*
Y1602362D01*
G02X867130Y1602363I-2162J1D01*
G01Y1607874D01*
G02X871454I2162J0D01*
G37*
G36*
G01X864366Y1603937D02*
Y1598424D01*
G02X860044Y1598425I-2161J1D01*
G01Y1603937D01*
G02X864366I2161J0D01*
G37*
G36*
G01X857280Y1607874D02*
Y1602362D01*
G02X852956Y1602363I-2162J1D01*
G01Y1607874D01*
G02X857280I2162J0D01*
G37*
G36*
G01X850194Y1603937D02*
Y1598424D01*
G02X845870Y1598425I-2162J1D01*
G01Y1603937D01*
G02X850194I2162J0D01*
G37*
G36*
G01X843106Y1636221D02*
Y1630708D01*
G02X838784Y1630709I-2161J1D01*
G01Y1636221D01*
G02X843106I2161J0D01*
G37*
G36*
G01X836020Y1646457D02*
Y1640944D01*
G02X831698Y1640945I-2161J1D01*
G01Y1646457D01*
G02X836020I2161J0D01*
G37*
G36*
G01X828934Y1636221D02*
Y1630708D01*
G02X824610Y1630709I-2162J1D01*
G01Y1636221D01*
G02X828934I2162J0D01*
G37*
G36*
G01Y1622048D02*
Y1616535D01*
G02X824610Y1616536I-2162J1D01*
G01Y1622048D01*
G02X828934I2162J0D01*
G37*
G36*
G01X843106Y1607874D02*
Y1602362D01*
G02X838784Y1602363I-2161J1D01*
G01Y1607874D01*
G02X843106I2161J0D01*
G37*
G36*
G01X836020Y1603937D02*
Y1598424D01*
G02X831698Y1598425I-2161J1D01*
G01Y1603937D01*
G02X836020I2161J0D01*
G37*
G36*
G01X828934Y1607874D02*
Y1602362D01*
G02X824610Y1602363I-2162J1D01*
G01Y1607874D01*
G02X828934I2162J0D01*
G37*
G36*
G01X566532Y91930D02*
Y86417D01*
G02X562208Y86418I-2162J1D01*
G01Y91930D01*
G02X566532I2162J0D01*
G37*
G36*
G01Y77756D02*
Y72244D01*
G02X562208Y72245I-2162J1D01*
G01Y77756D01*
G02X566532I2162J0D01*
G37*
G36*
G01Y120276D02*
Y114763D01*
G02X562208Y114764I-2162J1D01*
G01Y120276D01*
G02X566532I2162J0D01*
G37*
G36*
G01X519688Y72245D02*
Y77757D01*
G02X524012Y77756I2162J-1D01*
G01Y72245D01*
G02X519688I-2162J0D01*
G37*
G36*
G01X516926Y87993D02*
Y82480D01*
G02X512602Y82481I-2162J1D01*
G01Y87993D01*
G02X516926I2162J0D01*
G37*
G36*
G01X524012Y91930D02*
Y86417D01*
G02X519688Y86418I-2162J1D01*
G01Y91930D01*
G02X524012I2162J0D01*
G37*
G36*
G01X531098Y87993D02*
Y82480D01*
G02X526776Y82481I-2161J1D01*
G01Y87993D01*
G02X531098I2161J0D01*
G37*
G36*
G01X538186Y91930D02*
Y86417D01*
G02X533862Y86418I-2162J1D01*
G01Y91930D01*
G02X538186I2162J0D01*
G37*
G36*
G01Y77756D02*
Y72244D01*
G02X533862Y72245I-2162J1D01*
G01Y77756D01*
G02X538186I2162J0D01*
G37*
G36*
G01Y120276D02*
Y114763D01*
G02X533862Y114764I-2162J1D01*
G01Y120276D01*
G02X538186I2162J0D01*
G37*
G36*
G01X545272Y87993D02*
Y82480D01*
G02X540948Y82481I-2162J1D01*
G01Y87993D01*
G02X545272I2162J0D01*
G37*
G36*
G01X552358Y91930D02*
Y86417D01*
G02X548036Y86418I-2161J1D01*
G01Y91930D01*
G02X552358I2161J0D01*
G37*
G36*
G01X559444Y87993D02*
Y82480D01*
G02X555122Y82481I-2161J1D01*
G01Y87993D01*
G02X559444I2161J0D01*
G37*
G36*
G01X552358Y77756D02*
Y72244D01*
G02X548036Y72245I-2161J1D01*
G01Y77756D01*
G02X552358I2161J0D01*
G37*
G36*
G01X516926Y73819D02*
Y68306D01*
G02X512602Y68307I-2162J1D01*
G01Y73819D01*
G02X516926I2162J0D01*
G37*
G36*
G01X531098D02*
Y68306D01*
G02X526776Y68307I-2161J1D01*
G01Y73819D01*
G02X531098I2161J0D01*
G37*
G36*
G01X545272D02*
Y68306D01*
G02X540948Y68307I-2162J1D01*
G01Y73819D01*
G02X545272I2162J0D01*
G37*
G36*
G01X559444D02*
Y68306D01*
G02X555122Y68307I-2161J1D01*
G01Y73819D01*
G02X559444I2161J0D01*
G37*
G36*
G01X481492Y91930D02*
Y86417D01*
G02X477170Y86418I-2161J1D01*
G01Y91930D01*
G02X481492I2161J0D01*
G37*
G36*
G01Y77756D02*
Y72244D01*
G02X477170Y72245I-2161J1D01*
G01Y77756D01*
G02X481492I2161J0D01*
G37*
G36*
G01X467318Y91930D02*
Y86417D01*
G02X462996Y86418I-2161J1D01*
G01Y91930D01*
G02X467318I2161J0D01*
G37*
G36*
G01X474406Y87993D02*
Y82480D01*
G02X470082Y82481I-2162J1D01*
G01Y87993D01*
G02X474406I2162J0D01*
G37*
G36*
G01X467318Y77756D02*
Y72244D01*
G02X462996Y72245I-2161J1D01*
G01Y77756D01*
G02X467318I2161J0D01*
G37*
G36*
G01X477160Y114764D02*
Y120277D01*
G02X481502Y120276I2171J-1D01*
G01Y114764D01*
G02X477160I-2171J0D01*
G37*
G36*
G01X474406Y73819D02*
Y68306D01*
G02X470082Y68307I-2162J1D01*
G01Y73819D01*
G02X474406I2162J0D01*
G37*
G36*
G01X438972Y77756D02*
Y72244D01*
G02X434650Y72245I-2161J1D01*
G01Y77756D01*
G02X438972I2161J0D01*
G37*
G36*
G01X431886Y87993D02*
Y82480D01*
G02X427562Y82481I-2162J1D01*
G01Y87993D01*
G02X431886I2162J0D01*
G37*
G36*
G01X438972Y91930D02*
Y86417D01*
G02X434650Y86418I-2161J1D01*
G01Y91930D01*
G02X438972I2161J0D01*
G37*
G36*
G01X446060Y87993D02*
Y82480D01*
G02X441736Y82481I-2162J1D01*
G01Y87993D01*
G02X446060I2162J0D01*
G37*
G36*
G01X453146Y91930D02*
Y86417D01*
G02X448822Y86418I-2162J1D01*
G01Y91930D01*
G02X453146I2162J0D01*
G37*
G36*
G01X460232Y87993D02*
Y82480D01*
G02X455910Y82481I-2161J1D01*
G01Y87993D01*
G02X460232I2161J0D01*
G37*
G36*
G01X453146Y77756D02*
Y72244D01*
G02X448822Y72245I-2162J1D01*
G01Y77756D01*
G02X453146I2162J0D01*
G37*
G36*
G01X460232Y116339D02*
Y110826D01*
G02X455910Y110827I-2161J1D01*
G01Y116339D01*
G02X460232I2161J0D01*
G37*
G36*
G01X431886Y73819D02*
Y68306D01*
G02X427562Y68307I-2162J1D01*
G01Y73819D01*
G02X431886I2162J0D01*
G37*
G36*
G01X446060D02*
Y68306D01*
G02X441736Y68307I-2162J1D01*
G01Y73819D01*
G02X446060I2162J0D01*
G37*
G36*
G01X460232D02*
Y68306D01*
G02X455910Y68307I-2161J1D01*
G01Y73819D01*
G02X460232I2161J0D01*
G37*
G36*
G01X1898061Y1091290D02*
X1898062Y1091293D01*
Y1095715D01*
X1898061Y1095718D01*
G02X1901065I1502J36D01*
G01X1901064Y1095715D01*
Y1091293D01*
X1901065Y1091290D01*
G02X1898061I-1502J-36D01*
G37*
G36*
G01X1776852Y1095718D02*
Y1091290D01*
G02X1773848I-1502J-36D01*
G01Y1095718D01*
G02X1776852I1502J36D01*
G37*
G36*
G01X1652640D02*
Y1091290D01*
G02X1649636I-1502J-36D01*
G01Y1095718D01*
G02X1652640I1502J36D01*
G37*
G36*
G01X1525423Y1091290D02*
X1525424Y1091293D01*
Y1095715D01*
X1525423Y1095718D01*
G02X1528427I1502J36D01*
G01X1528426Y1095715D01*
Y1091293D01*
X1528427Y1091290D01*
G02X1525423I-1502J-36D01*
G37*
G36*
G01X1401211D02*
X1401212Y1091293D01*
Y1095715D01*
X1401211Y1095718D01*
G02X1404215I1502J36D01*
G01X1404214Y1095715D01*
Y1091293D01*
X1404215Y1091290D01*
G02X1401211I-1502J-36D01*
G37*
G36*
G01X1280002Y1095718D02*
Y1091290D01*
G02X1276998I-1502J-36D01*
G01Y1095718D01*
G02X1280002I1502J36D01*
G37*
G36*
G01X747549Y1091290D02*
X747550Y1091293D01*
Y1095715D01*
X747549Y1095718D01*
G02X750553I1502J36D01*
G01X750552Y1095715D01*
Y1091293D01*
X750553Y1091290D01*
G02X747549I-1502J-36D01*
G37*
G36*
G01X626340Y1095718D02*
Y1091290D01*
G02X623336I-1502J-36D01*
G01Y1095718D01*
G02X626340I1502J36D01*
G37*
G36*
G01X499123Y1091290D02*
X499124Y1091293D01*
Y1095715D01*
X499123Y1095718D01*
G02X502127I1502J36D01*
G01X502126Y1095715D01*
Y1091293D01*
X502127Y1091290D01*
G02X499123I-1502J-36D01*
G37*
G36*
G01X374911D02*
X374912Y1091293D01*
Y1095715D01*
X374911Y1095718D01*
G02X377915I1502J36D01*
G01X377914Y1095715D01*
Y1091293D01*
X377915Y1091290D01*
G02X374911I-1502J-36D01*
G37*
G36*
G01X253702Y1095718D02*
Y1091290D01*
G02X250698I-1502J-36D01*
G01Y1095718D01*
G02X253702I1502J36D01*
G37*
G36*
G01X129490D02*
Y1091290D01*
G02X126486I-1502J-36D01*
G01Y1095718D01*
G02X129490I1502J36D01*
G37*
G36*
G01X1879361Y1076290D02*
X1879362Y1076293D01*
Y1080715D01*
X1879361Y1080718D01*
G02X1882365I1502J36D01*
G01X1882364Y1080715D01*
Y1076293D01*
X1882365Y1076290D01*
G02X1879361I-1502J-36D01*
G37*
G36*
G01X1758152Y1080718D02*
Y1076290D01*
G02X1755148I-1502J-36D01*
G01Y1080718D01*
G02X1758152I1502J36D01*
G37*
G36*
G01X1633940D02*
Y1076290D01*
G02X1630936I-1502J-36D01*
G01Y1080718D01*
G02X1633940I1502J36D01*
G37*
G36*
G01X1506723Y1076290D02*
X1506724Y1076293D01*
Y1080715D01*
X1506723Y1080718D01*
G02X1509727I1502J36D01*
G01X1509726Y1080715D01*
Y1076293D01*
X1509727Y1076290D01*
G02X1506723I-1502J-36D01*
G37*
G36*
G01X1382511D02*
X1382512Y1076293D01*
Y1080715D01*
X1382511Y1080718D01*
G02X1385515I1502J36D01*
G01X1385514Y1080715D01*
Y1076293D01*
X1385515Y1076290D01*
G02X1382511I-1502J-36D01*
G37*
G36*
G01X1898061Y638534D02*
X1898062Y638537D01*
Y642959D01*
X1898061Y642962D01*
G02X1901065I1502J36D01*
G01X1901064Y642959D01*
Y638537D01*
X1901065Y638534D01*
G02X1898061I-1502J-36D01*
G37*
G36*
G01X1726852Y642962D02*
Y638534D01*
G02X1723848I-1502J-36D01*
G01Y642962D01*
G02X1726852I1502J36D01*
G37*
G36*
G01X1652640D02*
Y638534D01*
G02X1649636I-1502J-36D01*
G01Y642962D01*
G02X1652640I1502J36D01*
G37*
G36*
G01X1525423Y638534D02*
X1525424Y638537D01*
Y642959D01*
X1525423Y642962D01*
G02X1528427I1502J36D01*
G01X1528426Y642959D01*
Y638537D01*
X1528427Y638534D01*
G02X1525423I-1502J-36D01*
G37*
G36*
G01X1401211D02*
X1401212Y638537D01*
Y642959D01*
X1401211Y642962D01*
G02X1404215I1502J36D01*
G01X1404214Y642959D01*
Y638537D01*
X1404215Y638534D01*
G02X1401211I-1502J-36D01*
G37*
G36*
G01X1280002Y642962D02*
Y638534D01*
G02X1276998I-1502J-36D01*
G01Y642962D01*
G02X1280002I1502J36D01*
G37*
G36*
G01X747549Y638534D02*
X747550Y638537D01*
Y642959D01*
X747549Y642962D01*
G02X750553I1502J36D01*
G01X750552Y642959D01*
Y638537D01*
X750553Y638534D01*
G02X747549I-1502J-36D01*
G37*
G36*
G01X626340Y642962D02*
Y638534D01*
G02X623336I-1502J-36D01*
G01Y642962D01*
G02X626340I1502J36D01*
G37*
G36*
G01X499123Y638534D02*
X499124Y638537D01*
Y642959D01*
X499123Y642962D01*
G02X502127I1502J36D01*
G01X502126Y642959D01*
Y638537D01*
X502127Y638534D01*
G02X499123I-1502J-36D01*
G37*
G36*
G01X374911D02*
X374912Y638537D01*
Y642959D01*
X374911Y642962D01*
G02X377915I1502J36D01*
G01X377914Y642959D01*
Y638537D01*
X377915Y638534D01*
G02X374911I-1502J-36D01*
G37*
G36*
G01X253702Y642962D02*
Y638534D01*
G02X250698I-1502J-36D01*
G01Y642962D01*
G02X253702I1502J36D01*
G37*
G36*
G01X129490D02*
Y638534D01*
G02X126486I-1502J-36D01*
G01Y642962D01*
G02X129490I1502J36D01*
G37*
G36*
G01X1879361Y623534D02*
X1879362Y623537D01*
Y627959D01*
X1879361Y627962D01*
G02X1882365I1502J36D01*
G01X1882364Y627959D01*
Y623537D01*
X1882365Y623534D01*
G02X1879361I-1502J-36D01*
G37*
G36*
G01X1733152Y627962D02*
Y623534D01*
G02X1730148I-1502J-36D01*
G01Y627962D01*
G02X1733152I1502J36D01*
G37*
G36*
G01X1633940D02*
Y623534D01*
G02X1630936I-1502J-36D01*
G01Y627962D01*
G02X1633940I1502J36D01*
G37*
G36*
G01X1506723Y623534D02*
X1506724Y623537D01*
Y627959D01*
X1506723Y627962D01*
G02X1509727I1502J36D01*
G01X1509726Y627959D01*
Y623537D01*
X1509727Y623534D01*
G02X1506723I-1502J-36D01*
G37*
G36*
G01X1382511D02*
X1382512Y623537D01*
Y627959D01*
X1382511Y627962D01*
G02X1385515I1502J36D01*
G01X1385514Y627959D01*
Y623537D01*
X1385515Y623534D01*
G02X1382511I-1502J-36D01*
G37*
G36*
G01X1261302Y627962D02*
Y623534D01*
G02X1258298I-1502J-36D01*
G01Y627962D01*
G02X1261302I1502J36D01*
G37*
G36*
G01X1898061Y185778D02*
X1898062Y185781D01*
Y190203D01*
X1898061Y190206D01*
G02X1901065I1502J36D01*
G01X1901064Y190203D01*
Y185781D01*
X1901065Y185778D01*
G02X1898061I-1502J-36D01*
G37*
G36*
G01X1776852Y190206D02*
Y185778D01*
G02X1773848I-1502J-36D01*
G01Y190206D01*
G02X1776852I1502J36D01*
G37*
G36*
G01X1652640D02*
Y185778D01*
G02X1649636I-1502J-36D01*
G01Y190206D01*
G02X1652640I1502J36D01*
G37*
G36*
G01X1525423Y185778D02*
X1525424Y185781D01*
Y190203D01*
X1525423Y190206D01*
G02X1528427I1502J36D01*
G01X1528426Y190203D01*
Y185781D01*
X1528427Y185778D01*
G02X1525423I-1502J-36D01*
G37*
G36*
G01X747549D02*
X747550Y185781D01*
Y190203D01*
X747549Y190206D01*
G02X750553I1502J36D01*
G01X750552Y190203D01*
Y185781D01*
X750553Y185778D01*
G02X747549I-1502J-36D01*
G37*
G36*
G01X626340Y190206D02*
Y185778D01*
G02X623336I-1502J-36D01*
G01Y190206D01*
G02X626340I1502J36D01*
G37*
G36*
G01X499123Y185778D02*
X499124Y185781D01*
Y190203D01*
X499123Y190206D01*
G02X502127I1502J36D01*
G01X502126Y190203D01*
Y185781D01*
X502127Y185778D01*
G02X499123I-1502J-36D01*
G37*
G36*
G01X374911D02*
X374912Y185781D01*
Y190203D01*
X374911Y190206D01*
G02X377915I1502J36D01*
G01X377914Y190203D01*
Y185781D01*
X377915Y185778D01*
G02X374911I-1502J-36D01*
G37*
G36*
G01X253702Y190206D02*
Y185778D01*
G02X250698I-1502J-36D01*
G01Y190206D01*
G02X253702I1502J36D01*
G37*
G36*
G01X129490D02*
Y185778D01*
G02X126486I-1502J-36D01*
G01Y190206D01*
G02X129490I1502J36D01*
G37*
G36*
G01X1270436Y184325D02*
X1270439Y184324D01*
X1274861D01*
X1274864Y184325D01*
G02Y181321I36J-1502D01*
G01X1274861Y181322D01*
X1270439D01*
X1270436Y181321D01*
G02Y184325I-36J1502D01*
G37*
G36*
G01X1511414Y180198D02*
X1506986D01*
G02Y183202I-36J1502D01*
G01X1511414D01*
G02Y180198I36J-1502D01*
G37*
G36*
G01X1879361Y170778D02*
X1879362Y170781D01*
Y175203D01*
X1879361Y175206D01*
G02X1882365I1502J36D01*
G01X1882364Y175203D01*
Y170781D01*
X1882365Y170778D01*
G02X1879361I-1502J-36D01*
G37*
G36*
G01X1758152Y175206D02*
Y170778D01*
G02X1755148I-1502J-36D01*
G01Y175206D01*
G02X1758152I1502J36D01*
G37*
G36*
G01X1633940D02*
Y170778D01*
G02X1630936I-1502J-36D01*
G01Y175206D01*
G02X1633940I1502J36D01*
G37*
G36*
G01X1256786Y169325D02*
X1256789Y169324D01*
X1261211D01*
X1261214Y169325D01*
G02Y166321I36J-1502D01*
G01X1261211Y166322D01*
X1256789D01*
X1256786Y166321D01*
G02Y169325I-36J1502D01*
G37*
G36*
G01X970474Y-46450D02*
Y-70079D01*
G02X919290I-25592J0D01*
G01Y-46456D01*
G02X960345Y-26064I25592J0D01*
G03X960986Y-25741I241J319D01*
G02X970115Y-39262I14801J151D01*
G03X969576Y-39736I-153J-369D01*
G02X970474Y-46450I-24694J-6720D01*
G37*
G36*
G01X558368Y829921D02*
G02I-55120J0D01*
G37*
G36*
G01X1729038D02*
G02I-55121J0D01*
G37*
G54D56*
X111024Y153681D03*
Y606437D03*
Y1059193D03*
X235236Y153681D03*
Y606437D03*
Y1059193D03*
X359449Y153681D03*
Y606437D03*
Y1059193D03*
X483661Y153681D03*
Y606437D03*
Y1059193D03*
X607874Y153681D03*
Y606437D03*
Y1059193D03*
X732087Y153681D03*
Y606437D03*
Y1059193D03*
X949902Y-115157D03*
X1281693Y153681D03*
Y606437D03*
Y1059193D03*
X1405906Y153681D03*
Y606437D03*
Y1059193D03*
X1530118Y153681D03*
Y606437D03*
Y1059193D03*
X1654331Y153681D03*
Y606437D03*
Y1059193D03*
X1778543Y153681D03*
Y606437D03*
Y1059193D03*
X1902756Y153681D03*
Y606437D03*
Y1059193D03*
G54D57*
X111024Y302303D03*
Y755059D03*
Y1207815D03*
X235236Y302303D03*
Y755059D03*
Y1207815D03*
X359449Y302303D03*
Y755059D03*
Y1207815D03*
X483661Y302303D03*
Y755059D03*
Y1207815D03*
X607874Y302303D03*
Y755059D03*
Y1207815D03*
X732087Y302303D03*
Y755059D03*
Y1207815D03*
X1098524Y-115157D03*
X1281693Y302303D03*
Y755059D03*
Y1207815D03*
X1405906Y302303D03*
Y755059D03*
Y1207815D03*
X1530118Y302303D03*
Y755059D03*
Y1207815D03*
X1654331Y302303D03*
Y755059D03*
Y1207815D03*
X1778543Y302303D03*
Y755059D03*
Y1207815D03*
X1902756Y302303D03*
Y755059D03*
Y1207815D03*
G54D58*
X79000Y1301900D03*
X1826700Y77600D03*
X1908500Y1346800D03*
G54D55*
X80019Y51968D03*
X127263Y20472D03*
X631200Y51968D03*
X678444Y20472D03*
X1250689Y51969D03*
X1297933Y20472D03*
X1801870Y51969D03*
X1849114Y20472D03*
G54D62*
X942126Y58465D03*
Y346457D03*
Y437598D03*
Y725590D03*
X1110236Y58465D03*
Y346457D03*
Y437598D03*
Y725590D03*
G54D59*
X173228Y1114173D03*
X670079D03*
X1343700D03*
X1840551D03*
G54D61*
X496653Y80906D03*
X1465157D03*
G54D54*
X103642Y36220D03*
X173228Y1062992D03*
X421653Y1141732D03*
X654822Y36220D03*
X670079Y1062992D03*
X1274311Y36220D03*
X1343701Y1062992D03*
X1592126Y1141732D03*
X1825492Y36220D03*
X1840551Y1062992D03*
G54D64*
X1903346Y803937D03*
G54D53*
X31496Y882677D03*
X168307Y646457D03*
X660236D03*
X718110Y820866D03*
X904921Y564961D03*
X1366142Y646457D03*
X1462992Y866929D03*
X1602756Y646457D03*
X1894685Y21654D03*
G54D63*
X975788Y564961D03*
G54D60*
X496654Y110551D03*
X1465158D03*
G54D47*
X1797933Y1282666D03*
Y829910D03*
Y377154D03*
X1549901Y1282666D03*
Y829910D03*
Y377154D03*
X796457Y735444D03*
Y263003D03*
X627263Y1282666D03*
Y829910D03*
Y377154D03*
X131201Y1282666D03*
Y377154D03*
G54D50*
X1102113Y1394115D03*
X1098176Y1401201D03*
X1102113Y1351595D03*
X1098176Y1330335D03*
Y1372855D03*
X1126522Y1330335D03*
X1130459Y1351595D03*
X1102113Y1280729D03*
X1098176Y1301989D03*
X1102113Y1309075D03*
Y1323249D03*
X1130459Y1280729D03*
X1098176Y1259469D03*
Y1231123D03*
X1102113Y1238209D03*
X1126522Y1259469D03*
X1098176Y1188603D03*
X1102113Y1209863D03*
X1098176Y1216949D03*
X1126522Y1188603D03*
X1102113Y1167343D03*
X1098176Y1160257D03*
G54D48*
X1301870Y1282666D03*
Y829910D03*
Y377154D03*
X1181890Y1559854D03*
X1181870Y969280D03*
X1181890Y555917D03*
X961418Y1429932D03*
Y1087413D03*
X379232Y1282666D03*
Y829910D03*
Y377154D03*
X131200Y829910D03*
G54D52*
X1126522Y1401201D03*
X1130459Y1394115D03*
X1126522Y1372855D03*
X1130459Y1323249D03*
Y1309075D03*
X1126522Y1301989D03*
X1130459Y1238209D03*
X1126522Y1231123D03*
Y1216949D03*
X1130459Y1209863D03*
Y1167343D03*
X1126522Y1160257D03*
X1098176Y1002765D03*
X1102113Y1024025D03*
X1098176Y1031111D03*
X1126522D03*
X1130459Y1024025D03*
X1126522Y1002765D03*
G54D49*
X1102113Y1379942D03*
X1098176Y1387028D03*
X1102113Y1408288D03*
Y1365768D03*
X1098176Y1358682D03*
Y1344508D03*
X1102113Y1337422D03*
X1130459D03*
X1126522Y1344508D03*
Y1358682D03*
X1130459Y1365768D03*
X1098176Y1287816D03*
X1102113Y1294902D03*
X1098176Y1316162D03*
Y1273642D03*
X1102113Y1266556D03*
Y1252382D03*
X1098176Y1245296D03*
X1126522D03*
X1130459Y1252382D03*
Y1266556D03*
X1126522Y1273642D03*
X1102113Y1195690D03*
Y1181516D03*
X1098176Y1202776D03*
X1102113Y1224036D03*
X1130459Y1181516D03*
Y1195690D03*
X1098176Y1174430D03*
X1126522D03*
X1116286Y1038198D03*
G54D51*
X1130459Y1408288D03*
X1126522Y1387028D03*
X1130459Y1379942D03*
X1126522Y1316162D03*
X1130459Y1294902D03*
X1126522Y1287816D03*
X1130459Y1224036D03*
X1126522Y1202776D03*
X1102113Y1038198D03*
X1130459D03*
X1098176Y988592D03*
X1102113Y995678D03*
Y1009852D03*
X1098176Y1016938D03*
X1126522D03*
X1130459Y1009852D03*
Y995678D03*
X1126522Y988592D03*
G54D24*
X127988Y190242D03*
Y185742D03*
Y638498D03*
Y642998D03*
Y1091254D03*
Y1095754D03*
X252200Y190242D03*
Y185742D03*
Y638498D03*
Y642998D03*
Y1091254D03*
Y1095754D03*
X376413Y190242D03*
Y185742D03*
Y638498D03*
Y642998D03*
Y1091254D03*
Y1095754D03*
X500625Y190242D03*
Y185742D03*
Y638498D03*
Y642998D03*
Y1091254D03*
Y1095754D03*
X624838Y190242D03*
Y185742D03*
Y638498D03*
Y642998D03*
Y1091254D03*
Y1095754D03*
X749051Y190242D03*
Y185742D03*
Y638498D03*
Y642998D03*
Y1091254D03*
Y1095754D03*
X1070750Y1224035D03*
X1075250D03*
X1070750Y1209862D03*
X1075250D03*
X1070750Y1216949D03*
X1075250D03*
X1070750Y1231122D03*
X1075250D03*
X1070750Y1238209D03*
X1075250D03*
X1070750Y1245295D03*
X1075250D03*
X1070750Y1301988D03*
X1075250D03*
X1070750Y1309075D03*
X1075250D03*
X1070750Y1316161D03*
X1075250D03*
X1070750Y1323248D03*
X1075250D03*
X1070750Y1294902D03*
X1075250D03*
X1070750Y1330335D03*
X1075250D03*
X1070750Y1387028D03*
X1075250D03*
X1070750Y1394114D03*
X1075250D03*
X1070750Y1401201D03*
X1075250D03*
X1070750Y1408287D03*
X1075250D03*
X1070750Y1415374D03*
X1075250D03*
X1070750Y1379941D03*
X1075250D03*
X1274900Y182823D03*
X1270400D03*
X1261250Y167823D03*
X1256750D03*
X1278500Y638498D03*
Y642998D03*
X1259800Y627998D03*
Y623498D03*
Y1080754D03*
Y1076254D03*
X1278500Y1091254D03*
Y1095754D03*
X1402713Y185742D03*
Y190242D03*
X1380963Y167823D03*
X1385463D03*
X1402713Y638498D03*
Y642998D03*
X1384013Y627998D03*
Y623498D03*
Y1080754D03*
Y1076254D03*
X1402713Y1091254D03*
Y1095754D03*
X1511450Y181700D03*
X1506950D03*
X1508225Y627998D03*
Y623498D03*
Y1080754D03*
Y1076254D03*
X1526925Y185742D03*
Y190242D03*
Y638498D03*
Y642998D03*
Y1091254D03*
Y1095754D03*
X1651138Y185742D03*
Y190242D03*
X1632438Y175242D03*
Y170742D03*
X1651138Y638498D03*
Y642998D03*
X1632438Y627998D03*
Y623498D03*
Y1080754D03*
Y1076254D03*
X1651138Y1091254D03*
Y1095754D03*
X1756650Y175242D03*
Y170742D03*
X1725350Y638498D03*
Y642998D03*
X1731650Y627998D03*
Y623498D03*
X1756650Y1080754D03*
Y1076254D03*
X1775350Y185742D03*
Y190242D03*
Y1091254D03*
Y1095754D03*
X1899563Y185742D03*
Y190242D03*
X1880863Y175242D03*
Y170742D03*
X1899563Y638498D03*
Y642998D03*
X1880863Y627998D03*
Y623498D03*
Y1080754D03*
Y1076254D03*
X1899563Y1091254D03*
Y1095754D03*
G54D43*
X1039845Y1467746D03*
X1026345D03*
X1030845D03*
X1035345D03*
X1039845Y1463246D03*
X1026345D03*
X1030845D03*
X1035345D03*
X1005400Y1463157D03*
X1000900D03*
X996400D03*
X1009900D03*
X1005400Y1467657D03*
X1000900D03*
X996400D03*
X1009900D03*
X1035345Y1476746D03*
X1030845D03*
X1026345D03*
X1039845D03*
Y1472246D03*
X1026345D03*
X1030845D03*
X1035345D03*
X1005400Y1472157D03*
X1000900D03*
X996400D03*
X1009900D03*
Y1476657D03*
X1005400D03*
X1000900D03*
X996400D03*
X1023583Y1489593D03*
X995783D03*
X1000500Y1511400D03*
X1036578Y1511210D03*
X1014690Y1511178D03*
X1010190D03*
X1005690D03*
X1031790Y1511078D03*
X1027290D03*
X1019600Y1511100D03*
X1023583Y1501593D03*
Y1507593D03*
Y1495593D03*
X995783D03*
Y1501593D03*
Y1507593D03*
X1040583Y1517883D03*
X1031799Y1534392D03*
X1031882Y1528985D03*
X1026459Y1528919D03*
X1026376Y1534326D03*
X1014867D03*
X1014950Y1528919D03*
X1020290Y1534392D03*
X1020373Y1528985D03*
X1040500Y1529290D03*
X1040583Y1523883D03*
X1062700Y1463100D03*
X1058200D03*
X1067200D03*
X1062700Y1467600D03*
X1058200D03*
X1067200D03*
X1053700Y1463100D03*
Y1467600D03*
X1062700Y1472100D03*
X1058200D03*
X1067200D03*
Y1476600D03*
X1058200D03*
X1062700D03*
X1053700Y1472100D03*
Y1476600D03*
X1078683Y1489593D03*
X1051383D03*
X1041810Y1511084D03*
X1055310D03*
X1059810D03*
X1064310D03*
X1068810D03*
X1073310D03*
X1078683Y1495593D03*
Y1501593D03*
Y1507593D03*
Y1516593D03*
X1051383Y1495593D03*
Y1501593D03*
Y1507593D03*
X1078683Y1522593D03*
G54D14*
X19712Y1176350D03*
X25000Y1190400D03*
X64487Y201761D03*
X53087Y179561D03*
X49937Y219661D03*
X54437D03*
X58937D03*
X47607Y527511D03*
X61834Y527515D03*
X72500Y508600D03*
X67500D03*
X53087Y632317D03*
X58937Y672417D03*
X54437D03*
X49937D03*
X64487Y654417D03*
X27143Y663071D03*
X27510Y688422D03*
X58175Y981325D03*
X67500Y961355D03*
X72500D03*
X58937Y1125173D03*
X54437D03*
X49937D03*
X64487Y1107173D03*
X53027Y1085073D03*
X39325Y1131400D03*
X26723Y1116038D03*
X36848Y1173600D03*
X27090Y1141389D03*
X31500Y1224000D03*
X39425Y1226200D03*
X30000Y1190400D03*
X37225Y1230100D03*
X45518Y1336366D03*
X41381Y1335567D03*
X95437Y176661D03*
Y181161D03*
X73937Y201661D03*
X78937D03*
X83937D03*
X88937D03*
X85146Y621637D03*
X95437Y633917D03*
X88937Y654417D03*
X83937D03*
X78937D03*
X73937D03*
X101403Y981195D03*
X97063Y973225D03*
X98563Y977225D03*
X114100Y1002600D03*
X99700Y991400D03*
X108063Y991925D03*
X114300Y992362D03*
X104230Y992209D03*
X95537Y1082173D03*
Y1086673D03*
X73937Y1107173D03*
X78937D03*
X83937D03*
X88937D03*
X142687Y248100D03*
X145437Y265561D03*
X166400Y579400D03*
X168103Y569195D03*
X163763Y561225D03*
X165263Y565225D03*
X150253Y709713D03*
X145437Y717617D03*
X142687Y700767D03*
X140364Y749807D03*
X137163Y987125D03*
X130463Y983925D03*
X133063Y1012725D03*
X137063Y993725D03*
X145363Y997741D03*
X131110Y993257D03*
X148400Y1086900D03*
X145437Y1165673D03*
X150862Y1152723D03*
X142687Y1153523D03*
X148300Y1228800D03*
X148311Y1182767D03*
X135422Y1190937D03*
X140422D03*
X163500Y1345200D03*
X188699Y200561D03*
X177399Y179661D03*
X198149Y201661D03*
X203149D03*
X208149D03*
X213149D03*
X174149Y219661D03*
X178649D03*
X183149D03*
X171861Y527469D03*
X186088Y527473D03*
X196712Y508600D03*
X191712D03*
X210263Y546725D03*
X180800Y590600D03*
X207313Y598113D03*
X203763Y581725D03*
X212063Y585741D03*
X197810Y581257D03*
X174763Y579925D03*
X203863Y575125D03*
X181000Y580362D03*
X170930Y580209D03*
X197163Y571925D03*
X185149Y617949D03*
X199763Y600725D03*
X210000Y650000D03*
X182259Y672559D03*
X177759D03*
X173259D03*
X198149Y654417D03*
X203149D03*
X208149D03*
X213149D03*
X199900Y923200D03*
X216712Y961155D03*
X188399Y1102873D03*
X183149Y1125173D03*
X178649D03*
X174149D03*
X177105Y1094839D03*
X195100Y1096800D03*
X198149Y1107173D03*
X203149D03*
X208149D03*
X213149D03*
X219749Y176661D03*
Y181361D03*
X266899Y248011D03*
X219749Y618917D03*
Y623417D03*
X258600Y715500D03*
X266899Y700767D03*
X264731Y749551D03*
X223100Y920600D03*
X239000Y985600D03*
X221712Y961155D03*
X252100Y990100D03*
X244600Y1004600D03*
X261100Y1005700D03*
X227063Y994925D03*
X219749Y1082173D03*
X264864Y1120500D03*
X219749Y1086873D03*
X264594Y1190768D03*
X259594D03*
X312079Y68379D03*
X303029Y68429D03*
X313628Y112926D03*
X303000Y73500D03*
X314370Y118452D03*
X314439Y133669D03*
X312912Y201661D03*
X301612Y179661D03*
X298362Y219661D03*
X302862D03*
X307362D03*
X269649Y266261D03*
X291601Y418503D03*
X292153Y486059D03*
X306388Y486022D03*
X296032Y527469D03*
X310259Y527473D03*
X293763Y582925D03*
X301612Y632417D03*
X307362Y672417D03*
X302862D03*
X298362D03*
X312912Y654417D03*
X274520Y709457D03*
X268100Y982300D03*
X273300Y981700D03*
X280800Y1011900D03*
X281200Y1033000D03*
X271100Y1063200D03*
X281500Y1036744D03*
X307362Y1125173D03*
X302862D03*
X298362D03*
X313232Y1106499D03*
X301327Y1085173D03*
X269649Y1165673D03*
X275385Y1152596D03*
X271165Y1147172D03*
X315500Y1216700D03*
X276100Y1229100D03*
X273243Y1182915D03*
X286925Y1201945D03*
X295900Y1339700D03*
X296100Y1335100D03*
X279900Y1328300D03*
X283700D03*
X286100Y1349659D03*
X292600Y1337367D03*
X289510Y1342259D03*
X354100Y62100D03*
X322500Y68345D03*
X334845Y58745D03*
X361776Y70842D03*
X335081Y104081D03*
X339219Y95188D03*
X339914Y82415D03*
X344304Y82439D03*
X345321Y102400D03*
X347647Y95614D03*
X353001Y114815D03*
X347881Y114881D03*
X351416Y95788D03*
X337641Y114910D03*
X334947Y94605D03*
X342761Y114861D03*
X350441Y117541D03*
X337721Y129821D03*
X323813Y118512D03*
X341114Y123622D03*
X345321Y118921D03*
X323813Y133722D03*
X344062Y176461D03*
X343962Y181161D03*
X322362Y201661D03*
X327362D03*
X332362D03*
X337362D03*
X320474Y379474D03*
X316534D03*
X320474Y363234D03*
X316534D03*
X320925Y485385D03*
X315925D03*
X320925Y508600D03*
X315925D03*
X333682Y621858D03*
X343862Y633917D03*
X322362Y654417D03*
X327362D03*
X332362D03*
X337362D03*
X320474Y832229D03*
X316534D03*
X320925Y938140D03*
X315600Y933600D03*
X335300Y926900D03*
X337100Y972100D03*
X320925Y961355D03*
X315925D03*
X344737Y995637D03*
X350673Y1031200D03*
X344062Y1082073D03*
Y1086773D03*
X322362Y1107173D03*
X327362D03*
X332362D03*
X337362D03*
X331679Y1175800D03*
X377144Y84720D03*
X377944Y95929D03*
X390412Y248011D03*
X386800Y263800D03*
X393862Y719917D03*
X398677Y709385D03*
X391112Y700767D03*
X388788Y749479D03*
X407714Y761291D03*
X398254Y763517D03*
X408672Y1008038D03*
X388888Y1118173D03*
X393679Y1157480D03*
X383191Y1170203D03*
X391112Y1153500D03*
X398527Y1188659D03*
X383849Y1190833D03*
X388849Y1191148D03*
X398527Y1233336D03*
X437124Y201661D03*
X429224Y176300D03*
X446951Y213656D03*
X451951D03*
X456951D03*
X431574Y219661D03*
X427074D03*
X422574D03*
X441645Y288847D03*
Y284647D03*
X456190Y354105D03*
X444687Y379474D03*
X440747D03*
X444687Y363234D03*
X440747D03*
X452800Y420912D03*
X418600Y445462D03*
X421700Y450200D03*
X445138Y487743D03*
X440138D03*
X447533Y475900D03*
X458679Y470700D03*
X450500Y459562D03*
X416303Y486022D03*
X430538Y485985D03*
X420182Y527432D03*
X434409Y527436D03*
X440138Y508600D03*
X445138D03*
X425824Y632317D03*
X457853Y622091D03*
X437224Y654417D03*
X431574Y672417D03*
X427074D03*
X422574D03*
X456574Y654417D03*
X451574D03*
X446574D03*
X444687Y832229D03*
X440747D03*
X444687Y816765D03*
X440747D03*
X445138Y938140D03*
X440138D03*
X435082Y915200D03*
X437600Y917800D03*
X445582Y925352D03*
X449137Y967757D03*
X440138Y961355D03*
X445138D03*
X429613Y1017920D03*
X432657Y1015102D03*
X442600Y998300D03*
X413000Y1054200D03*
X442473Y1068726D03*
X447173D03*
X456919Y1121725D03*
X447919D03*
X452419D03*
X441976Y1107576D03*
X446627Y1112973D03*
X441400Y1169400D03*
X416900Y1221800D03*
X412300Y1326200D03*
X415422Y1352000D03*
X422373Y1359747D03*
X418922Y1356522D03*
X462200Y173109D03*
X468472Y182441D03*
X461951Y213656D03*
X462133Y473300D03*
X481533Y480875D03*
X497351Y531531D03*
X501023Y534941D03*
X472022Y582062D03*
X468174Y633917D03*
X461574Y654417D03*
X465200Y1018200D03*
X506500Y1051900D03*
X504724Y1107073D03*
X505874Y1134773D03*
X506700Y1145973D03*
X508103Y1190557D03*
X509180Y145419D03*
X546009Y187821D03*
X539584Y184694D03*
X542155Y187543D03*
X557057Y220152D03*
X553674Y220121D03*
X550219Y220111D03*
X515324Y252511D03*
X553742Y267705D03*
X510700Y277200D03*
X534905Y354105D03*
X539350Y487659D03*
X534350D03*
X510621Y486059D03*
X524856Y486022D03*
X518700Y548700D03*
X553279Y523331D03*
X514500Y524469D03*
X528727Y524973D03*
X553279Y513331D03*
X530130Y547167D03*
X534350Y508600D03*
X539350D03*
X557279Y570331D03*
X527179Y568731D03*
X549937Y632317D03*
X555787Y672417D03*
X551287D03*
X546787D03*
X509996Y716996D03*
X522773Y709638D03*
X515324Y700667D03*
X512884Y749732D03*
X530800Y1028300D03*
X515800Y1028000D03*
X556022Y1042817D03*
X552436Y1042494D03*
X546787Y1125173D03*
X551287D03*
X555787D03*
X549773Y1085173D03*
X514474Y1107073D03*
X519474D03*
X524474D03*
X529474D03*
X509037Y1136700D03*
X524828Y1159231D03*
X522867Y1190284D03*
X513103Y1190557D03*
X522867Y1231097D03*
X520600Y1324100D03*
X536000Y1359826D03*
X541362D03*
X518397Y1360000D03*
X512900Y1345600D03*
X553587Y1346026D03*
X527000Y1340600D03*
X521500Y1342800D03*
X566271Y167387D03*
X561437Y197249D03*
X592767Y179277D03*
X598236Y181981D03*
X582697Y200744D03*
X577697D03*
X572697D03*
X587697D03*
X568899Y379474D03*
X564959D03*
X568899Y363234D03*
X564959D03*
X602379Y547831D03*
X570779Y542831D03*
X568779Y512831D03*
X575779D03*
X593079Y516531D03*
Y512531D03*
X585479Y537731D03*
Y543994D03*
X572229Y520081D03*
X580279Y512831D03*
X571408Y577450D03*
X584279Y577431D03*
X575779D03*
X579718D03*
X592779D03*
X588779D03*
X562279D03*
X567641Y577473D03*
X571529Y562951D03*
X579529D03*
X602779Y552331D03*
X592387Y629417D03*
Y634017D03*
X561437Y654417D03*
X585787D03*
X580787D03*
X575787D03*
X570787D03*
X568899Y832229D03*
X564959D03*
X593365Y877358D03*
X592614Y882300D03*
X569350Y941640D03*
X564350D03*
X569350Y961355D03*
X564350D03*
X571400Y1000100D03*
X592387Y1082173D03*
X561337Y1107173D03*
X592387Y1086873D03*
X570787Y1107173D03*
X575787D03*
X580787D03*
X585787D03*
X600640Y1171000D03*
X592400Y1214456D03*
X607929Y112329D03*
X619171D03*
X639537Y248011D03*
X642287Y266461D03*
X652663Y502400D03*
X647663D03*
X612000Y502300D03*
X624028Y503558D03*
X638263Y503494D03*
X615119Y551586D03*
X627000Y538581D03*
Y542909D03*
X609334Y538306D03*
Y543306D03*
X619560Y547201D03*
X627863Y522000D03*
X642509Y520667D03*
X652663Y516600D03*
X647663D03*
X615147Y565956D03*
X637213Y582155D03*
X623236Y562574D03*
X642287Y719817D03*
X647207Y709555D03*
X639537Y700767D03*
X637318Y749649D03*
X645200Y1067800D03*
X636803Y1167864D03*
X642942Y1156818D03*
X632603Y1136225D03*
X647716Y1154150D03*
X639537Y1153523D03*
X627632Y1217300D03*
X647126Y1189513D03*
X632316Y1190474D03*
X637316D03*
X687566Y109568D03*
X663449Y115606D03*
X690807Y103298D03*
X677450Y185669D03*
X685250Y199493D03*
X699950Y200846D03*
X694950D03*
X674313Y220374D03*
X669813D03*
X689232Y355251D03*
X693112Y385976D03*
X689172D03*
Y358978D03*
X658646Y515180D03*
X658681Y571798D03*
X654681D03*
X683341Y580479D03*
X689747D03*
X682000Y628449D03*
X685550Y654417D03*
X679929Y673058D03*
X675429D03*
X670929D03*
X700000Y654417D03*
X695000D03*
X658574Y930100D03*
X677457Y944796D03*
X688563Y961355D03*
X693563D03*
X663800Y1018300D03*
X682200Y1026500D03*
X674300Y1001620D03*
X685250Y1102873D03*
X680000Y1125173D03*
X675500D03*
X671000D03*
X674700Y1098500D03*
X695000Y1107173D03*
X700000D03*
X664000Y1278100D03*
X673000Y1354100D03*
X747242Y197553D03*
X717188Y176461D03*
X716600Y181161D03*
X709950Y200846D03*
X704950D03*
X705348Y478425D03*
X716600Y629417D03*
Y633917D03*
X710000Y654417D03*
X705000D03*
X724283Y860689D03*
X737984Y861689D03*
X741883Y861389D03*
X733883Y935689D03*
X736883Y938689D03*
Y929189D03*
Y933689D03*
X747383Y924689D03*
X733883Y940689D03*
X736462Y948996D03*
X736883Y943189D03*
X716600Y1081973D03*
Y1086673D03*
X705000Y1107173D03*
X710000D03*
X728174Y1275611D03*
X725678Y1272799D03*
X722790Y1270557D03*
X720446Y1267427D03*
X731500Y1277811D03*
X757020Y159692D03*
X758619Y168537D03*
X767405Y210364D03*
X763188Y172500D03*
X789739Y365493D03*
X754500Y668741D03*
X755000Y677700D03*
X765124Y864089D03*
X766707Y872260D03*
X762453Y872413D03*
X765025Y867802D03*
X757664Y868974D03*
X753893Y912630D03*
X776400Y956500D03*
X780800Y959300D03*
X786800Y1016000D03*
X784000Y1024000D03*
X759500Y1056100D03*
X779535Y1180469D03*
X792263Y1178661D03*
Y1174461D03*
Y1170261D03*
X752500Y1167500D03*
X756250Y1151750D03*
X784544Y1210178D03*
Y1205978D03*
X779535Y1193469D03*
Y1189269D03*
Y1184669D03*
X797177Y1189537D03*
X797225Y1185337D03*
X792263Y1182861D03*
X792336Y1319537D03*
X782230Y1323670D03*
X769728Y1325747D03*
X785340Y1320410D03*
X789549Y1322310D03*
X777009Y1322690D03*
X781290Y1328490D03*
X772900Y1328550D03*
X790290Y1328410D03*
X785640Y1328370D03*
X796848Y1469724D03*
X829921Y-458D03*
X825984D03*
X833724Y-3346D03*
X833671Y254D03*
X806299Y-458D03*
X802362D03*
X814173D03*
X810236D03*
X822047D03*
X818110D03*
X845661Y-3642D03*
X843463Y530D03*
X806314Y35952D03*
X802350Y35923D03*
X842470Y41295D03*
X841733Y36654D03*
X818300Y39845D03*
X814300D03*
Y43845D03*
X818300D03*
X810301Y78654D03*
X805301D03*
X802801Y75654D03*
X807801D03*
X812801D03*
X846400Y473900D03*
X839500Y508500D03*
X809015Y661000D03*
X804015D03*
X808920Y652340D03*
Y656460D03*
X806515Y664000D03*
X802036Y1164244D03*
X803438Y1139700D03*
X809600Y1236300D03*
X804600D03*
X802100Y1233300D03*
X807100D03*
X812100D03*
X806952Y1460496D03*
X806568Y1464275D03*
X802433Y1461619D03*
X800900Y1465234D03*
X800462Y1469231D03*
X834813Y1528889D03*
X834974Y1533243D03*
X886322Y69D03*
X867080Y393D03*
X886427Y3802D03*
X873892Y287D03*
X886418Y-7350D03*
X849484Y649D03*
X886351Y-3735D03*
X857513Y659D03*
X885448Y37380D03*
X877265Y52540D03*
X881265D03*
X885265D03*
X873265D03*
X869265D03*
X869459Y56626D03*
Y61626D03*
X869044Y66985D03*
X873044D03*
X877139Y66926D03*
X885265Y60540D03*
Y56540D03*
X881750Y37397D03*
X858496Y37121D03*
X854180Y36996D03*
X852995Y40965D03*
X856995D03*
X886073Y78824D03*
X885464Y83201D03*
X878549Y78905D03*
Y82905D03*
X869044Y70985D03*
X873044D03*
X882549Y76905D03*
Y80905D03*
X872796Y251714D03*
X881549Y326304D03*
X890982Y349498D03*
X874800Y355798D03*
X887100Y359100D03*
X887500Y378495D03*
X875132Y399200D03*
X878732D03*
Y395600D03*
X875132D03*
X878732Y392000D03*
X875132D03*
X880932Y406400D03*
Y402800D03*
X877332Y406400D03*
Y402800D03*
X874807Y375193D03*
X866276Y454900D03*
X866317Y446725D03*
X880932Y410000D03*
X877332D03*
X857300Y454300D03*
X862000Y453600D03*
X852000Y454200D03*
X866321Y451300D03*
X878500Y476000D03*
X878193Y467707D03*
X866278Y459562D03*
X870600Y476900D03*
X851800Y477200D03*
X874715Y707651D03*
X871115D03*
X867515D03*
X884700Y705200D03*
X881100D03*
X877500D03*
X887600Y811900D03*
X891200Y838200D03*
X878673Y804527D03*
X874569Y811300D03*
X885882Y861618D03*
X894965Y843500D03*
X877673Y868873D03*
X888962Y843262D03*
X873647Y861653D03*
X882333Y896320D03*
X895616Y985932D03*
X863800Y1309876D03*
X872164Y1350464D03*
X873259Y1365805D03*
X872181Y1354764D03*
X886792Y1404100D03*
X873918Y1411149D03*
X873800Y1418200D03*
X871432Y1420932D03*
X874900Y1421900D03*
X877406Y1419124D03*
X875740Y1415070D03*
X882226Y1404197D03*
X873694Y1404575D03*
X873700Y1375746D03*
X873570Y1380401D03*
X872192Y1424492D03*
X882000Y1432600D03*
X870921Y1432300D03*
X888800Y1493500D03*
X876514Y1514948D03*
X863851Y1501681D03*
X877828Y1500379D03*
X892966Y1508549D03*
X893036Y1512600D03*
X877946Y1496527D03*
X876096Y1505499D03*
X889002Y1489638D03*
X873972Y1472467D03*
X873922Y1477766D03*
X860179Y1491170D03*
X893020Y1566530D03*
X876200Y1553900D03*
X892700Y1543900D03*
X892558Y1528458D03*
X889300Y1551000D03*
X876190Y1537187D03*
X876100Y1549000D03*
X876200Y1558400D03*
X892700Y1524700D03*
X848551Y1542440D03*
X922687Y93D03*
X928138Y-8453D03*
X942000Y752850D03*
X897000Y839000D03*
X903000Y842500D03*
X920810Y902210D03*
X928100Y900650D03*
X900615Y909723D03*
X902571Y906534D03*
X903368Y934568D03*
X904594Y931141D03*
X916204Y938572D03*
X917550Y934742D03*
X901540Y937712D03*
X896679Y927505D03*
X896420Y916712D03*
X898468Y912970D03*
X931085Y936172D03*
X941274Y900845D03*
X934142Y974344D03*
X939481Y980230D03*
X912994Y971921D03*
X910397Y979189D03*
X902991Y982230D03*
X909826Y982874D03*
X905271Y974586D03*
X899846Y971468D03*
X898617Y975434D03*
X895837Y978389D03*
X896629Y982285D03*
X935623Y971054D03*
X904601Y998556D03*
X910040Y1006613D03*
X911807Y1002342D03*
X919656Y998764D03*
X939544Y1003485D03*
X903442Y1003265D03*
X896371Y1002112D03*
X936378Y1035722D03*
X920770Y1067389D03*
X921149Y1062424D03*
X914948Y1063255D03*
X908477Y1061823D03*
X910387Y1055344D03*
X904875Y1051177D03*
X896500Y1341800D03*
X936959Y1360143D03*
X896212Y1345788D03*
X895900Y1390100D03*
X896200Y1386000D03*
X896100Y1393800D03*
X896200Y1397900D03*
Y1405300D03*
X896100Y1401600D03*
X923829Y1389012D03*
X936994Y1379895D03*
X927601Y1384433D03*
X923486Y1384268D03*
X906600Y1461600D03*
X909400Y1459200D03*
X910000Y1464900D03*
X905500Y1467161D03*
X938000Y1499200D03*
X942000Y1499500D03*
X922500Y1499700D03*
X908742Y1477427D03*
X908542Y1481127D03*
X922500Y1509700D03*
X941000Y1564200D03*
X937000D03*
X926500Y1556700D03*
X931500Y1564200D03*
X913250Y1547700D03*
X940000Y1529200D03*
X940750Y1549200D03*
X900000Y1526500D03*
X897400Y1574000D03*
X897038Y1577600D03*
X911516Y1573202D03*
X911616Y1576802D03*
X911710Y1582375D03*
X911094Y1585923D03*
X924059Y1647700D03*
X981700Y-115500D03*
X976713Y-115570D03*
X991713Y-115413D03*
X989316Y-94984D03*
X992185Y-54411D03*
X989050Y-70850D03*
X990565Y130230D03*
Y135230D03*
Y125230D03*
X985688Y362549D03*
X977794Y695103D03*
X952200Y742600D03*
X957100Y742900D03*
X977622Y699464D03*
X953200Y736700D03*
X956900Y737600D03*
X949048Y755225D03*
X952476Y753652D03*
X951300Y747900D03*
X956200Y748200D03*
X957320Y769818D03*
X947866Y763541D03*
X957629Y766231D03*
X952820Y769518D03*
X944500Y760750D03*
X961100Y931640D03*
X960503Y936185D03*
X967583Y933607D03*
X968698Y928957D03*
X974484Y935078D03*
X976419Y931628D03*
X976460Y927891D03*
X981679Y936678D03*
X976213Y938846D03*
X966000Y937500D03*
X953013Y960147D03*
X947174Y957150D03*
X979020Y960000D03*
Y956200D03*
X973900Y960000D03*
Y956200D03*
X968780Y960000D03*
Y956200D03*
X987734Y979575D03*
X951200Y1030700D03*
X946700D03*
X947759Y998726D03*
X961220Y1001600D03*
Y1005400D03*
X966340Y1001600D03*
Y1005400D03*
X971460Y1001600D03*
Y1005400D03*
X974020Y1026200D03*
Y1022400D03*
X968900Y1026200D03*
Y1022400D03*
X963780Y1026200D03*
Y1022400D03*
X956600Y1001700D03*
Y1005700D03*
X964537Y1160310D03*
X958870Y1163617D03*
X962941Y1165929D03*
X967497Y1168802D03*
X957871Y1171219D03*
X963000Y1174427D03*
X969463Y1177599D03*
X972924Y1158033D03*
X954395Y1145604D03*
X982387Y1183598D03*
X951525Y1369107D03*
X955500Y1369000D03*
X946300Y1499300D03*
X969198Y1505851D03*
X969472Y1501978D03*
X950300Y1499500D03*
X975813Y1556916D03*
X953500Y1563200D03*
X962000Y1564200D03*
X958000D03*
X949000D03*
X945000D03*
X972001Y1533926D03*
X975813Y1545916D03*
X954700Y1524100D03*
Y1530363D03*
X974787Y1525100D03*
Y1529300D03*
X948750Y1549200D03*
X979963Y1545689D03*
X1004213Y-95837D03*
X998045Y-79300D03*
X993816Y-95184D03*
X1036713Y-115500D03*
X1007582Y-39418D03*
X1000300Y-74200D03*
X1032080Y-45980D03*
X1004082Y-38200D03*
X1000418Y-69982D03*
X993000Y-60600D03*
X1019118Y-34382D03*
X1019082Y-71000D03*
X1026717Y-11646D03*
X1021086Y-11682D03*
X1010650Y49950D03*
Y67650D03*
X1030775Y130016D03*
X1030890Y137780D03*
X993565Y137730D03*
Y132730D03*
Y127730D03*
X1030774Y133840D03*
X1030758Y126274D03*
X1030825Y122335D03*
X1020250Y357188D03*
X1040180Y437510D03*
X1038215Y877191D03*
X1034271Y876911D03*
X1011100Y904600D03*
X1025000Y897700D03*
X1036431Y929752D03*
X1037083Y933300D03*
X1016842Y916445D03*
X1035947Y948800D03*
X1028657Y1009103D03*
X1020654Y1023940D03*
X1018094Y1021240D03*
X1015534Y1023840D03*
X1007849Y1033743D03*
X996600D03*
X1012974Y1021240D03*
X1013700Y1007640D03*
X1009509Y1009850D03*
X1037282Y995028D03*
X1005294Y997940D03*
Y1001740D03*
X1010414Y997940D03*
Y1001740D03*
X1023214Y1007140D03*
X1007372Y1023832D03*
X1017194Y1033840D03*
X1026900Y1129466D03*
X1022400Y1129183D03*
X1036160Y1095500D03*
Y1091700D03*
Y1111900D03*
X994923Y1137488D03*
X995948Y1184250D03*
X1017354Y1196124D03*
X1021061Y1198543D03*
X1016835Y1323916D03*
X1025335Y1324216D03*
X1016672Y1338228D03*
X1025284Y1341216D03*
X1025335Y1337616D03*
Y1330916D03*
X1016600Y1332000D03*
X1033000Y1416125D03*
X1028000Y1404700D03*
Y1411000D03*
X1031500Y1408000D03*
X1020854Y1455075D03*
X1016854D03*
X1051713Y-114887D03*
X1056713Y-115413D03*
X1086713Y-115570D03*
X1081713D03*
X1071713D03*
X1066713D03*
X1041713Y-115465D03*
X1085300Y-90700D03*
X1079455Y-30742D03*
X1043000Y-67600D03*
X1043112Y-34912D03*
X1066600Y-72800D03*
X1066225Y-40278D03*
X1054593Y-51122D03*
X1078900Y-45782D03*
X1085800Y-57100D03*
X1070918Y-73618D03*
X1043303Y-27685D03*
X1045873Y-24660D03*
X1043513Y-21696D03*
X1077505Y22405D03*
X1076418Y31082D03*
X1076944Y35182D03*
X1077260Y42612D03*
X1077400Y52000D03*
X1077082Y38982D03*
X1076905Y46195D03*
X1076299Y27282D03*
X1054800Y22405D03*
X1041500Y382858D03*
X1078100Y392600D03*
Y397600D03*
Y402600D03*
X1072600Y392500D03*
Y397500D03*
Y402500D03*
X1045292Y384688D03*
X1074425Y447225D03*
X1071950Y453288D03*
X1072600Y407500D03*
X1078100Y407600D03*
X1043674Y451921D03*
X1043500Y446600D03*
X1042800Y442000D03*
X1069018Y456900D03*
X1065985Y460500D03*
X1054419Y839493D03*
Y828081D03*
X1050763Y829163D03*
X1086600Y833200D03*
X1044101Y927130D03*
X1083633Y932172D03*
X1073408Y942399D03*
X1058571Y943852D03*
X1053099Y1021657D03*
X1048512Y1021378D03*
X1041616Y997225D03*
X1069000Y1067100D03*
X1083355Y1125903D03*
X1070155D03*
X1048960Y1113900D03*
Y1117700D03*
X1041280Y1121500D03*
Y1113900D03*
Y1117700D03*
X1081078Y1095362D03*
X1083660Y1092700D03*
X1041280Y1095500D03*
Y1091700D03*
Y1100500D03*
X1048960Y1095500D03*
Y1091700D03*
Y1099300D03*
X1054080Y1113900D03*
Y1117700D03*
X1068700Y1108700D03*
X1083355Y1116103D03*
X1070155D03*
X1075600Y1179090D03*
X1053743Y1174221D03*
X1046900Y1168000D03*
X1052522Y1145153D03*
X1076032Y1191144D03*
X1070000Y1184100D03*
X1079500Y1276100D03*
X1047000Y1258687D03*
X1051300Y1253300D03*
X1077300Y1271700D03*
X1042343Y1324216D03*
X1048251Y1349992D03*
X1046372Y1356326D03*
X1042343Y1337616D03*
X1042443Y1342668D03*
X1042343Y1330916D03*
X1076754Y1455075D03*
X1072754D03*
X1044654D03*
X1048654D03*
X1100929Y-90371D03*
X1116600Y-85538D03*
X1106300Y-94800D03*
X1089318Y-91682D03*
X1101246Y-31005D03*
X1124024Y-30840D03*
X1128765Y-34297D03*
X1094200Y-38400D03*
X1111254Y-31020D03*
X1105328Y-31005D03*
X1094300Y-60300D03*
X1103300Y-60000D03*
X1115603Y-60293D03*
X1134110Y176500D03*
X1136203Y167600D03*
X1089300Y836100D03*
X1119419Y888607D03*
X1116419Y896107D03*
Y891107D03*
X1119419Y893607D03*
Y898607D03*
X1110447Y944217D03*
X1105447D03*
X1100447D03*
X1102947Y947217D03*
X1107947D03*
X1091400Y1070900D03*
X1091494Y1075994D03*
X1097800Y1070700D03*
X1097500Y1075100D03*
X1103800Y1070600D03*
Y1075600D03*
X1128900Y1067200D03*
X1119500Y1125100D03*
X1115000D03*
X1123600Y1096400D03*
X1123838Y1092800D03*
X1123600Y1100000D03*
X1133981Y1096283D03*
X1134002Y1092600D03*
X1134103Y1099881D03*
X1137436Y1124750D03*
X1128800Y1125100D03*
X1092200Y1125800D03*
X1103064Y1113626D03*
X1099020Y1112276D03*
X1096460Y1115125D03*
X1092742Y1113462D03*
X1134100Y1433300D03*
X1146768Y-31238D03*
X1139808Y-31171D03*
X1149699Y-35153D03*
X1142293Y-37522D03*
X1181568Y55168D03*
X1181868Y50568D03*
Y45568D03*
X1181568Y60168D03*
X1178268Y64068D03*
X1183268D03*
X1178268Y85068D03*
Y69068D03*
Y89068D03*
X1183268Y85068D03*
Y69068D03*
Y89068D03*
X1178656Y104637D03*
X1176952Y93390D03*
X1140550Y179200D03*
X1142800Y174637D03*
X1140500Y171400D03*
X1171749Y259163D03*
X1175400Y258800D03*
X1176300Y284500D03*
X1180953Y284800D03*
X1185588Y285035D03*
X1185000Y281343D03*
X1176100Y270603D03*
X1176300Y288600D03*
X1169768Y730300D03*
Y723100D03*
Y726700D03*
X1175568Y712300D03*
X1171968D03*
X1175568Y715900D03*
X1171968D03*
X1173368Y730300D03*
X1171968Y719500D03*
X1175568D03*
X1173368Y726700D03*
Y723100D03*
X1138198Y832424D03*
X1172736Y1031786D03*
X1177036Y1032086D03*
X1170140Y1043939D03*
X1152880Y1097672D03*
X1152682Y1091138D03*
X1149984Y1115804D03*
X1143550Y1120317D03*
X1139524Y1121817D03*
X1152800Y1223062D03*
X1152700Y1216213D03*
X1150420Y1229800D03*
X1181400Y1266100D03*
X1184000Y1260100D03*
X1149823Y1233373D03*
X1144000Y1310000D03*
X1150232Y1316358D03*
X1154500Y1327500D03*
X1150911Y1329500D03*
X1147900Y1421500D03*
X1143900Y1431000D03*
X1142400Y1427700D03*
X1146002Y1427906D03*
X1145007Y1424446D03*
X1148556Y1425056D03*
X1188268Y64068D03*
Y85068D03*
Y69068D03*
Y89068D03*
X1215795Y181242D03*
X1215600Y261800D03*
X1219962Y244739D03*
X1186600Y253200D03*
X1215547Y246355D03*
X1194700Y261700D03*
X1189700Y308527D03*
X1190200Y285023D03*
X1201835Y305319D03*
X1193800Y307857D03*
X1198100Y306858D03*
X1194600Y288237D03*
X1197000Y279400D03*
X1226045Y431102D03*
X1194000Y1037900D03*
X1232842Y1140722D03*
X1198130Y1151410D03*
X1205303Y1227604D03*
X1250016Y247017D03*
X1253300Y227700D03*
X1262075Y297100D03*
X1250500Y266600D03*
X1239362Y524168D03*
X1253511Y517606D03*
X1264878Y508068D03*
X1268400Y716100D03*
X1265891Y699583D03*
X1263250Y823436D03*
X1243200Y933700D03*
X1259808Y927260D03*
X1271296Y986867D03*
X1274413Y984613D03*
X1279599Y976407D03*
X1253338Y980784D03*
X1253975Y970147D03*
X1264269Y981248D03*
X1263618Y990606D03*
X1268378Y990608D03*
X1239900Y1024000D03*
X1256142Y1029316D03*
X1252400Y1054100D03*
X1272755Y1137293D03*
X1260300Y1169000D03*
X1240314Y1139741D03*
X1268948Y1150173D03*
X1254800Y1269600D03*
X1240276Y1356700D03*
X1323829Y55929D03*
X1328295Y55800D03*
X1320055Y68000D03*
X1304563Y100771D03*
X1299569Y100639D03*
X1312263Y95463D03*
X1327921Y78900D03*
X1308228Y93399D03*
X1315961Y98112D03*
X1314794Y162944D03*
X1324134Y126967D03*
X1313127Y120839D03*
X1315118Y126967D03*
X1324207Y138756D03*
X1315102Y137903D03*
X1330807Y181473D03*
X1311750Y187911D03*
X1326637Y226568D03*
X1316637D03*
X1321637D03*
X1326500Y627917D03*
X1311750Y640667D03*
X1312000Y615417D03*
X1318000Y680417D03*
X1323000D03*
X1328000D03*
X1316000Y772200D03*
X1310500Y774700D03*
X1312767Y885535D03*
X1286000Y982200D03*
X1284695Y956586D03*
X1326500Y1080673D03*
X1317400Y1068000D03*
X1309600Y1068173D03*
X1311750Y1093423D03*
X1328000Y1133173D03*
X1318000D03*
X1323000D03*
X1351200Y68600D03*
X1359350Y66350D03*
X1358355Y81488D03*
X1338215Y107586D03*
X1336034Y82542D03*
X1334383Y75892D03*
X1340961Y78811D03*
X1343521Y85472D03*
X1347607Y101337D03*
X1346081Y80671D03*
X1348641Y83326D03*
X1352351Y101724D03*
X1350779Y106496D03*
X1348641Y110550D03*
X1333281Y85133D03*
X1341922Y105649D03*
X1354500Y75400D03*
X1349931Y138361D03*
X1338400Y126015D03*
X1333988Y161471D03*
X1358971Y129978D03*
X1362685Y130109D03*
X1351665Y128325D03*
X1343112Y128997D03*
X1364017Y123277D03*
X1337662Y137188D03*
X1334500Y202548D03*
Y207548D03*
Y212548D03*
Y217548D03*
X1372274Y272874D03*
X1355991Y275272D03*
X1374338Y292900D03*
X1358573Y290900D03*
X1375700Y413400D03*
X1357316Y542311D03*
X1346057Y529857D03*
X1338100Y520300D03*
X1353500Y518900D03*
X1359882Y508014D03*
X1364882D03*
X1336000Y627000D03*
X1334000Y666417D03*
Y661917D03*
Y657417D03*
Y652917D03*
X1373553Y700994D03*
X1347600Y734078D03*
X1344062Y737800D03*
X1354500Y747304D03*
X1360920Y749829D03*
X1334300Y771200D03*
X1338729Y776131D03*
X1338700Y771500D03*
X1334329Y775831D03*
X1373519Y761900D03*
X1341219Y933282D03*
X1346080Y907004D03*
X1378100Y972100D03*
X1339404Y969600D03*
X1353762Y969886D03*
X1367382Y961355D03*
X1362382D03*
X1349829Y1014840D03*
X1365551Y1028250D03*
X1361074Y1114565D03*
X1334500Y1104700D03*
Y1111173D03*
Y1116173D03*
Y1121173D03*
X1360238Y1143867D03*
X1370716Y1148037D03*
X1351321Y1152553D03*
X1355733Y1241900D03*
X1369600Y1330100D03*
X1373700Y1330000D03*
X1365551Y1353500D03*
X1427663Y167032D03*
X1384475Y255839D03*
X1384713Y323200D03*
X1414882Y397271D03*
X1395300Y438500D03*
X1418225Y421700D03*
X1418493Y531407D03*
X1425600Y544600D03*
X1418507Y517007D03*
X1407936Y552099D03*
Y548099D03*
X1425200Y540100D03*
X1414319Y523900D03*
X1396297Y573397D03*
X1421239Y558029D03*
X1396297Y579803D03*
X1421239Y562229D03*
X1383952Y717435D03*
X1392355Y886696D03*
X1391000Y932400D03*
X1380300Y930200D03*
X1384800Y1002666D03*
X1383899Y1166690D03*
X1388500Y1224900D03*
X1381800Y1329600D03*
X1463804Y138605D03*
X1436204Y159247D03*
X1435963Y183833D03*
X1450713Y173049D03*
X1456373Y168971D03*
X1458764Y212625D03*
Y208025D03*
Y203425D03*
X1442213Y227661D03*
X1447213D03*
X1452213D03*
X1458764Y217225D03*
X1444238Y349852D03*
X1439654D03*
X1431909Y359311D03*
X1463000Y490638D03*
X1457200Y549600D03*
X1470700Y522100D03*
X1456439Y515000D03*
X1448261D03*
X1435200D03*
X1443700D03*
X1460200D03*
X1452200D03*
X1465700D03*
X1439200D03*
X1442500Y548400D03*
X1456450Y529600D03*
X1448450D03*
X1459200Y579600D03*
X1452200D03*
X1442500Y554700D03*
X1455750Y572350D03*
X1474700Y569100D03*
X1447700Y579600D03*
X1474700Y579100D03*
X1450713Y627817D03*
X1435963Y640667D03*
X1455202Y618557D03*
X1436213Y615417D03*
X1442213Y680417D03*
X1447213D03*
X1452213D03*
X1458713Y658417D03*
Y663417D03*
Y668417D03*
Y652217D03*
X1474083Y764750D03*
X1471608Y768500D03*
X1435300Y882700D03*
X1440500Y893500D03*
X1448000Y910000D03*
X1463616Y969265D03*
X1451800Y1004700D03*
X1450713Y1080673D03*
X1446213Y1062300D03*
X1436213Y1068173D03*
X1442213Y1132173D03*
X1447213D03*
X1452213D03*
X1439750Y1096673D03*
X1461713Y1123173D03*
Y1118173D03*
Y1113173D03*
X1461700Y1107200D03*
X1470953Y1152427D03*
X1475953D03*
X1467000Y1221800D03*
X1473600Y1242777D03*
X1511177Y125412D03*
X1499775Y248061D03*
X1508925Y323200D03*
X1481938Y489926D03*
X1485932Y522335D03*
X1500600Y523300D03*
X1502400Y544100D03*
X1497849Y545264D03*
X1486594Y508098D03*
X1491594D03*
X1513200Y519700D03*
X1509800Y516100D03*
X1494400Y560400D03*
Y556100D03*
X1500539Y739639D03*
X1498000Y743000D03*
X1505900Y717600D03*
X1495480Y704558D03*
X1489000Y723000D03*
X1476558Y759088D03*
X1479033Y762259D03*
X1486600Y786559D03*
X1505900Y930400D03*
X1521200Y928000D03*
X1503394Y968179D03*
X1477974Y970044D03*
X1491594Y961355D03*
X1486594D03*
X1484000Y992315D03*
X1481500Y995758D03*
X1478194Y1017166D03*
X1481529Y1030500D03*
X1485608Y1113628D03*
X1504200Y1171300D03*
X1485833Y1140369D03*
X1495900Y1149000D03*
X1491662Y1351300D03*
X1494662Y1336000D03*
X1497200Y1342500D03*
X1501600Y1342300D03*
X1560425Y162661D03*
X1560175Y187911D03*
X1566425Y227661D03*
X1571425D03*
X1568500Y438500D03*
Y544100D03*
X1568000Y548500D03*
X1555175Y642667D03*
X1560425Y615417D03*
X1566425Y677417D03*
X1571425D03*
X1565593Y654856D03*
X1565618Y660773D03*
Y665773D03*
Y670773D03*
X1526000Y728000D03*
X1570500Y888400D03*
X1570425Y1062000D03*
X1560425Y1068173D03*
X1547800Y1098819D03*
X1552800D03*
X1557800D03*
X1562800D03*
X1556231Y1134920D03*
X1558650Y1217426D03*
X1574925Y175061D03*
X1579371Y166019D03*
X1582925Y210661D03*
Y205661D03*
Y200661D03*
X1576425Y227661D03*
X1621100Y244661D03*
X1582925Y215661D03*
X1586596Y518723D03*
X1600745Y517561D03*
X1615807Y508600D03*
X1610807D03*
X1574925Y627817D03*
X1578926Y618657D03*
X1576425Y677417D03*
X1620469Y697517D03*
X1584800Y895800D03*
X1587400Y912200D03*
X1608200Y914400D03*
X1618200Y916800D03*
X1574576Y976700D03*
X1615494Y973179D03*
X1587829Y969191D03*
X1602187Y969970D03*
X1615807Y961355D03*
X1610807D03*
X1580381Y1007066D03*
X1602400Y1019366D03*
X1620059Y1032932D03*
X1574925Y1080673D03*
X1603425Y1105040D03*
Y1100040D03*
X1598425Y1102440D03*
Y1107440D03*
X1620059Y1128071D03*
X1615909Y1150262D03*
X1613400Y1236500D03*
X1622738Y264938D03*
X1621138Y719238D03*
X1643344Y887455D03*
X1646013Y884255D03*
X1639644Y889755D03*
X1633600Y936300D03*
X1621787Y917108D03*
X1636400Y925800D03*
X1629094Y975179D03*
X1624198Y1111309D03*
X1633138Y1165673D03*
X1635688Y1153773D03*
X1624500Y1349100D03*
X1684638Y162661D03*
X1684388Y187911D03*
X1699138Y175061D03*
X1703584Y166019D03*
X1707138Y210661D03*
Y205661D03*
Y200661D03*
X1690638Y227661D03*
X1695638D03*
X1700638D03*
X1707138Y215661D03*
X1711061Y518470D03*
X1684388Y638324D03*
X1699138Y627917D03*
X1705000Y618667D03*
X1684638Y615417D03*
X1699638Y675417D03*
X1689638D03*
X1694638D03*
X1707100Y652500D03*
X1707138Y658417D03*
Y663417D03*
Y668417D03*
X1692100Y923600D03*
X1704010Y898000D03*
X1674814Y961977D03*
X1677056Y954636D03*
X1680012Y952402D03*
X1685047Y1014966D03*
X1680087Y1023983D03*
X1671422Y1009266D03*
X1690279Y1011526D03*
X1691771Y1035163D03*
X1699138Y1080573D03*
X1685100Y1054000D03*
X1679300Y1043169D03*
X1694638Y1063600D03*
X1684638Y1068173D03*
X1700638Y1131673D03*
X1695638D03*
X1690638D03*
X1684388Y1091723D03*
X1707138Y1111173D03*
Y1116173D03*
Y1121173D03*
X1707200Y1105200D03*
X1702838Y1215300D03*
X1710617Y1231429D03*
X1715049Y1234000D03*
X1746400Y244561D03*
X1747550Y265000D03*
X1725100Y519300D03*
X1740019Y508600D03*
X1735019D03*
X1752000Y929200D03*
X1755010Y966285D03*
X1740019Y961355D03*
X1735019D03*
X1738863Y985225D03*
X1755900Y1014600D03*
X1740499Y1008223D03*
X1749863Y1003925D03*
X1756100Y1004362D03*
X1746030Y1004209D03*
X1737241Y997843D03*
X1740363Y989225D03*
X1733245Y1115503D03*
X1751400Y1173900D03*
X1732768Y1141697D03*
X1748100Y1153673D03*
X1718117Y1152553D03*
X1723117D03*
X1755900Y1212704D03*
X1740000Y1346900D03*
X1808850Y162661D03*
X1808600Y187911D03*
Y640667D03*
X1808850Y615417D03*
X1766721Y720500D03*
X1813851Y927406D03*
X1768692Y966073D03*
X1797463Y968652D03*
X1806077Y961860D03*
X1782666Y961344D03*
X1777666D03*
X1783778Y970371D03*
X1774863Y1024725D03*
X1788726Y1034726D03*
X1778863Y1005725D03*
X1787163Y1009741D03*
X1772863Y1005304D03*
X1778963Y999125D03*
X1772263Y995925D03*
X1812050Y1071223D03*
X1805250Y1067973D03*
X1841021Y152968D03*
X1845517Y158475D03*
X1856219Y201661D03*
X1823350Y175161D03*
X1827796Y166019D03*
X1831350Y210661D03*
Y205661D03*
Y200661D03*
X1850669Y219661D03*
X1846169D03*
X1841669D03*
X1824850Y227661D03*
X1819850D03*
X1814850D03*
X1831350Y215661D03*
X1834896Y518597D03*
X1849045Y517435D03*
X1859232Y508600D03*
X1823350Y627917D03*
X1827667Y618703D03*
X1840855Y606200D03*
X1845417Y611231D03*
X1841669Y672417D03*
X1846169D03*
X1850669D03*
X1814850Y680417D03*
X1819850D03*
X1824850D03*
X1856219Y654417D03*
X1831350Y658417D03*
Y663417D03*
Y668417D03*
X1831300Y652600D03*
X1855676Y800787D03*
X1824170Y886349D03*
X1819541Y921500D03*
X1823937Y890883D03*
X1821152Y907899D03*
X1823350Y1080673D03*
X1858046Y1092779D03*
X1836953Y1103391D03*
X1850363Y1115037D03*
X1847506Y1118794D03*
X1851565Y1118784D03*
X1850280Y1111373D03*
X1816046Y1098532D03*
X1836200Y1130000D03*
X1828850Y1106173D03*
Y1111173D03*
Y1116173D03*
Y1121173D03*
X1824850Y1133173D03*
X1814850D03*
X1819850D03*
X1840585Y1151653D03*
X1836400Y1151900D03*
X1842000Y1344700D03*
X1869500Y179134D03*
X1876938Y181062D03*
X1865669Y201661D03*
X1870669D03*
X1875669D03*
X1880669D03*
X1864232Y508600D03*
X1869500Y633500D03*
X1878900Y637000D03*
X1879669Y652917D03*
X1874669D03*
X1869669D03*
X1864669D03*
X1884800Y890750D03*
X1902441Y888500D03*
X1896943Y894350D03*
X1891676Y917759D03*
X1884500Y912500D03*
X1904000Y933500D03*
Y929000D03*
Y925000D03*
X1906500Y893400D03*
X1909358Y897500D03*
X1904000Y938000D03*
X1873001Y901396D03*
X1904000Y921000D03*
X1872190Y936766D03*
X1867963Y996425D03*
X1887402Y1050193D03*
X1872162Y1055426D03*
X1864617Y1040934D03*
X1888085Y1059938D03*
X1876662Y1055426D03*
X1864833Y1091419D03*
X1870779Y1091763D03*
X1875779D03*
X1880779D03*
X1873500Y1329000D03*
X1911676Y893469D03*
G54D32*
X429724Y68307D03*
X458071D03*
X443898D03*
X429724Y116339D03*
Y96654D03*
Y102166D03*
Y110827D03*
Y87993D03*
Y82481D03*
Y73819D03*
X443898Y116339D03*
X458071D03*
X436811Y114764D03*
X450984D03*
X443898Y96654D03*
X458071D03*
X443898Y102166D03*
X458071D03*
X436811Y100591D03*
X450984D03*
X436811Y106103D03*
X450984D03*
X443898Y110827D03*
X458071D03*
Y87993D03*
Y82481D03*
X450984Y91930D03*
Y86418D03*
X443898Y87993D03*
Y82481D03*
X436811Y91930D03*
Y86418D03*
X458071Y73819D03*
X450984Y77756D03*
Y72245D03*
X443898Y73819D03*
X436811Y77756D03*
Y72245D03*
Y120276D03*
X450984D03*
X472244Y68307D03*
X465157Y114764D03*
X472244Y116339D03*
X479331Y114764D03*
X465157Y100591D03*
Y106103D03*
X472244Y96654D03*
Y102166D03*
X479331Y100591D03*
Y106103D03*
X472244Y110827D03*
X479331Y91930D03*
Y86418D03*
X472244Y87993D03*
Y82481D03*
X465157Y91930D03*
Y86418D03*
X479331Y77756D03*
Y72245D03*
X472244Y73819D03*
X465157Y77756D03*
Y72245D03*
Y120276D03*
X479331D03*
X514764Y68307D03*
X543110D03*
X528937D03*
X557283D03*
X514764Y116339D03*
Y110827D03*
Y102166D03*
Y96654D03*
Y87993D03*
Y82481D03*
Y73819D03*
X550197Y114764D03*
X536024D03*
X521850D03*
X543110Y116339D03*
X528937D03*
X543110Y110827D03*
X528937D03*
X550197Y106103D03*
X536024D03*
X521850D03*
X550197Y100591D03*
X536024D03*
X521850D03*
X543110Y102166D03*
X528937D03*
X543110Y96654D03*
X528937D03*
X550197Y91930D03*
Y86418D03*
X543110Y87993D03*
Y82481D03*
X536024Y91930D03*
Y86418D03*
X528937Y87993D03*
Y82481D03*
X521850Y91930D03*
Y86418D03*
X550197Y77756D03*
Y72245D03*
X543110Y73819D03*
X536024Y77756D03*
Y72245D03*
X528937Y73819D03*
X521850Y77756D03*
Y72245D03*
X557283Y116339D03*
Y110827D03*
Y102166D03*
Y96654D03*
Y87993D03*
Y82481D03*
Y73819D03*
X550197Y120276D03*
X536024D03*
X521850D03*
X564370Y114764D03*
Y106103D03*
Y100591D03*
Y91930D03*
Y86418D03*
Y77756D03*
Y72245D03*
Y120276D03*
X833859Y1598425D03*
Y1603937D03*
Y1612599D03*
X840945Y1602363D03*
X826772D03*
X840945Y1607874D03*
X826772D03*
X840945Y1616536D03*
X826772D03*
X833859Y1618111D03*
Y1626772D03*
Y1632284D03*
Y1640945D03*
Y1646457D03*
X840945Y1622048D03*
X826772D03*
X840945Y1630709D03*
X826772D03*
X840945Y1636221D03*
X826772D03*
X840945Y1644882D03*
X826772D03*
X840945Y1650394D03*
X826772D03*
X876378Y1598425D03*
X862205D03*
X848032D03*
X876378Y1603937D03*
X862205D03*
X848032D03*
X876378Y1612599D03*
X862205D03*
X848032D03*
X890552Y1602363D03*
X869292D03*
X855118D03*
X890552Y1607874D03*
X869292D03*
X855118D03*
X890552Y1612205D03*
Y1616536D03*
X869292D03*
X855118D03*
X876378Y1618111D03*
X862205D03*
X848032D03*
X876378Y1626772D03*
X862205D03*
X848032D03*
X876378Y1632284D03*
X862205D03*
X848032D03*
X876378Y1640945D03*
X862205D03*
X848032D03*
X876378Y1646457D03*
X862205D03*
X848032D03*
X890552Y1622048D03*
X869292D03*
X855118D03*
X890552Y1626378D03*
Y1630709D03*
X869292D03*
X855118D03*
X890552Y1636221D03*
X869292D03*
X855118D03*
X890552Y1640551D03*
Y1644882D03*
X869292D03*
X855118D03*
X890552Y1650394D03*
X869292D03*
X855118D03*
X911811Y1603937D03*
Y1608268D03*
Y1612599D03*
X904725Y1602363D03*
Y1607874D03*
Y1612205D03*
Y1616536D03*
X911811Y1594095D03*
Y1598425D03*
X904725Y1598032D03*
X897638Y1598425D03*
Y1603937D03*
Y1608268D03*
Y1612599D03*
X911811Y1632284D03*
Y1636614D03*
Y1640945D03*
Y1646457D03*
Y1650788D03*
X904725Y1630709D03*
Y1636221D03*
Y1640551D03*
Y1644882D03*
Y1650394D03*
X911811Y1618111D03*
Y1622441D03*
Y1626772D03*
X904725Y1622048D03*
Y1626378D03*
X897638Y1618111D03*
Y1622441D03*
Y1626772D03*
Y1632284D03*
Y1636614D03*
Y1640945D03*
Y1646457D03*
Y1650788D03*
X1095420Y988592D03*
X1100932D03*
X1109593D03*
X1115105D03*
X1123766D03*
X1129278D03*
X1099357Y995678D03*
X1104869D03*
X1113530D03*
X1119042D03*
X1127703D03*
X1133215D03*
X1095420Y1002765D03*
X1100932D03*
X1109593D03*
X1115105D03*
X1123766D03*
X1129278D03*
X1099357Y1009852D03*
X1104869D03*
X1113530D03*
X1119042D03*
X1127703D03*
X1133215D03*
X1095420Y1016938D03*
X1100932D03*
X1109593D03*
X1115105D03*
X1123766D03*
X1129278D03*
X1099357Y1024025D03*
X1104869D03*
X1113530D03*
X1119042D03*
X1127703D03*
X1133215D03*
X1095420Y1031111D03*
X1100932D03*
X1109593D03*
X1115105D03*
X1123766D03*
X1129278D03*
X1099357Y1038198D03*
X1104869D03*
X1113530D03*
X1119042D03*
X1127703D03*
X1133215D03*
X1095420Y1160257D03*
Y1174430D03*
X1100932Y1160257D03*
Y1174430D03*
X1109593Y1160257D03*
Y1174430D03*
X1115105Y1160257D03*
Y1174430D03*
X1123766Y1160257D03*
Y1174430D03*
X1129278Y1160257D03*
Y1174430D03*
X1099357Y1167343D03*
X1104869D03*
X1113530D03*
X1119042D03*
X1127703D03*
X1133215D03*
X1095420Y1188603D03*
Y1202776D03*
Y1216949D03*
X1100932Y1188603D03*
Y1202776D03*
Y1216949D03*
X1109593Y1188603D03*
Y1202776D03*
Y1216949D03*
X1115105Y1188603D03*
Y1202776D03*
Y1216949D03*
X1123766Y1188603D03*
Y1202776D03*
Y1216949D03*
X1129278Y1188603D03*
Y1202776D03*
Y1216949D03*
X1099357Y1181516D03*
Y1195690D03*
Y1209863D03*
Y1224036D03*
X1104869Y1181516D03*
Y1195690D03*
Y1209863D03*
Y1224036D03*
X1113530Y1181516D03*
Y1195690D03*
Y1209863D03*
Y1224036D03*
X1119042Y1181516D03*
Y1195690D03*
Y1209863D03*
Y1224036D03*
X1127703Y1181516D03*
Y1195690D03*
Y1209863D03*
Y1224036D03*
X1133215Y1181516D03*
Y1195690D03*
Y1209863D03*
Y1224036D03*
X1095420Y1231123D03*
Y1245296D03*
Y1259469D03*
Y1273642D03*
X1100932Y1231123D03*
Y1245296D03*
Y1259469D03*
Y1273642D03*
X1109593Y1231123D03*
Y1245296D03*
Y1259469D03*
Y1273642D03*
X1115105Y1231123D03*
Y1245296D03*
Y1259469D03*
Y1273642D03*
X1123766Y1231123D03*
Y1245296D03*
Y1259469D03*
Y1273642D03*
X1129278Y1231123D03*
Y1245296D03*
Y1259469D03*
Y1273642D03*
X1099357Y1238209D03*
Y1252382D03*
Y1266556D03*
X1104869Y1238209D03*
Y1252382D03*
Y1266556D03*
X1113530Y1238209D03*
Y1252382D03*
Y1266556D03*
X1119042Y1238209D03*
Y1252382D03*
Y1266556D03*
X1127703Y1238209D03*
Y1252382D03*
Y1266556D03*
X1133215Y1238209D03*
Y1252382D03*
Y1266556D03*
X1095420Y1287816D03*
Y1301989D03*
Y1316162D03*
X1100932Y1287816D03*
Y1301989D03*
Y1316162D03*
X1109593Y1287816D03*
Y1301989D03*
Y1316162D03*
X1115105Y1287816D03*
Y1301989D03*
Y1316162D03*
X1123766Y1287816D03*
Y1301989D03*
Y1316162D03*
X1129278Y1287816D03*
Y1301989D03*
Y1316162D03*
X1099357Y1280729D03*
Y1294902D03*
Y1309075D03*
Y1323249D03*
X1104869Y1280729D03*
Y1294902D03*
Y1309075D03*
Y1323249D03*
X1113530Y1280729D03*
Y1294902D03*
Y1309075D03*
Y1323249D03*
X1119042Y1280729D03*
Y1294902D03*
Y1309075D03*
Y1323249D03*
X1127703Y1280729D03*
Y1294902D03*
Y1309075D03*
Y1323249D03*
X1133215Y1280729D03*
Y1294902D03*
Y1309075D03*
Y1323249D03*
X1095420Y1330335D03*
Y1344508D03*
Y1358682D03*
Y1372855D03*
X1100932Y1330335D03*
Y1344508D03*
Y1358682D03*
Y1372855D03*
X1109593Y1330335D03*
Y1344508D03*
Y1358682D03*
Y1372855D03*
X1115105Y1330335D03*
Y1344508D03*
Y1358682D03*
Y1372855D03*
X1123766Y1330335D03*
Y1344508D03*
Y1358682D03*
Y1372855D03*
X1129278Y1330335D03*
Y1344508D03*
Y1358682D03*
Y1372855D03*
X1099357Y1337422D03*
Y1351595D03*
Y1365768D03*
X1104869Y1337422D03*
Y1351595D03*
Y1365768D03*
X1113530Y1337422D03*
Y1351595D03*
Y1365768D03*
X1119042Y1337422D03*
Y1351595D03*
Y1365768D03*
X1127703Y1337422D03*
Y1351595D03*
Y1365768D03*
X1133215Y1337422D03*
Y1351595D03*
Y1365768D03*
X1095420Y1387028D03*
Y1401201D03*
X1100932Y1387028D03*
Y1401201D03*
X1109593Y1387028D03*
Y1401201D03*
X1115105Y1387028D03*
Y1401201D03*
X1123766Y1387028D03*
Y1401201D03*
X1129278Y1387028D03*
Y1401201D03*
X1099357Y1379942D03*
Y1394115D03*
Y1408288D03*
X1104869Y1379942D03*
Y1394115D03*
Y1408288D03*
X1113530Y1379942D03*
Y1394115D03*
Y1408288D03*
X1119042Y1379942D03*
Y1394115D03*
Y1408288D03*
X1127703Y1379942D03*
Y1394115D03*
Y1408288D03*
X1133215Y1379942D03*
Y1394115D03*
Y1408288D03*
X1398228Y68307D03*
X1426575D03*
X1412402D03*
X1398228Y116339D03*
Y96654D03*
Y102166D03*
Y110827D03*
Y87993D03*
Y82481D03*
Y73819D03*
X1412402Y116339D03*
X1426575D03*
X1405315Y114764D03*
X1419488D03*
X1412402Y96654D03*
X1426575D03*
X1412402Y102166D03*
X1426575D03*
X1405315Y100591D03*
X1419488D03*
X1405315Y106103D03*
X1419488D03*
X1412402Y110827D03*
X1426575D03*
Y87993D03*
Y82481D03*
X1419488Y91930D03*
Y86418D03*
X1412402Y87993D03*
Y82481D03*
X1405315Y91930D03*
Y86418D03*
X1426575Y73819D03*
X1419488Y77756D03*
Y72245D03*
X1412402Y73819D03*
X1405315Y77756D03*
Y72245D03*
Y120276D03*
X1419488D03*
X1440748Y68307D03*
X1433661Y114764D03*
X1440748Y116339D03*
X1447835Y114764D03*
X1433661Y100591D03*
Y106103D03*
X1440748Y96654D03*
Y102166D03*
X1447835Y100591D03*
Y106103D03*
X1440748Y110827D03*
X1447835Y91930D03*
Y86418D03*
X1440748Y87993D03*
Y82481D03*
X1433661Y91930D03*
Y86418D03*
X1447835Y77756D03*
Y72245D03*
X1440748Y73819D03*
X1433661Y77756D03*
Y72245D03*
Y120276D03*
X1447835D03*
X1483268Y68307D03*
X1511614D03*
X1497441D03*
X1483268Y116339D03*
Y110827D03*
Y102166D03*
Y96654D03*
Y87993D03*
Y82481D03*
Y73819D03*
X1518701Y114764D03*
X1504528D03*
X1490354D03*
X1511614Y116339D03*
X1497441D03*
X1511614Y110827D03*
X1497441D03*
X1518701Y106103D03*
X1504528D03*
X1490354D03*
X1518701Y100591D03*
X1504528D03*
X1490354D03*
X1511614Y102166D03*
X1497441D03*
X1511614Y96654D03*
X1497441D03*
X1518701Y91930D03*
Y86418D03*
X1511614Y87993D03*
Y82481D03*
X1504528Y91930D03*
Y86418D03*
X1497441Y87993D03*
Y82481D03*
X1490354Y91930D03*
Y86418D03*
X1518701Y77756D03*
Y72245D03*
X1511614Y73819D03*
X1504528Y77756D03*
Y72245D03*
X1497441Y73819D03*
X1490354Y77756D03*
Y72245D03*
X1518701Y120276D03*
X1504528D03*
X1490354D03*
X1525787Y68307D03*
X1532874Y114764D03*
X1525787Y116339D03*
Y110827D03*
X1532874Y106103D03*
Y100591D03*
X1525787Y102166D03*
Y96654D03*
X1532874Y91930D03*
Y86418D03*
X1525787Y87993D03*
Y82481D03*
X1532874Y77756D03*
Y72245D03*
X1525787Y73819D03*
X1532874Y120276D03*
G54D41*
X988795Y1571058D03*
Y1576658D03*
X1026106Y1545595D03*
Y1539995D03*
X1031706Y1545595D03*
Y1539995D03*
X1020574Y1540059D03*
Y1545659D03*
X1039758Y1559605D03*
X1014974Y1540059D03*
Y1545659D03*
X1039358Y1565405D03*
X1033717Y1563634D03*
X1028223Y1563763D03*
X1022623D03*
X994305Y1566342D03*
X1017023Y1563763D03*
X1011476Y1565175D03*
X1005658Y1565005D03*
X1000058D03*
X1039958Y1553705D03*
Y1548105D03*
Y1542505D03*
X1039358Y1571005D03*
Y1576605D03*
X1005658Y1575905D03*
X1033917Y1574834D03*
X1033717Y1569234D03*
X1000058Y1575905D03*
X1028423Y1574963D03*
X1028223Y1569363D03*
X994460Y1577240D03*
X1022823Y1574963D03*
X1022623Y1569363D03*
X1017223Y1574963D03*
X1017023Y1569363D03*
X994305Y1571942D03*
X1011676Y1576375D03*
X1011476Y1570775D03*
X1005658Y1570605D03*
X1000058D03*
X1078358Y1561105D03*
Y1566705D03*
X1072758Y1561105D03*
Y1566705D03*
X1067158Y1561105D03*
Y1566705D03*
X1061558Y1561105D03*
Y1566705D03*
X1055768Y1566675D03*
X1055418Y1560785D03*
X1055618Y1554885D03*
Y1549285D03*
Y1543685D03*
X1078358Y1572305D03*
X1072758D03*
X1067158D03*
X1061558D03*
X1055768Y1572275D03*
Y1577875D03*
G54D20*
X111024Y302303D03*
Y755059D03*
Y1207815D03*
X235236Y302303D03*
Y755059D03*
Y1207815D03*
X359449Y302303D03*
Y755059D03*
Y1207815D03*
X483661Y302303D03*
Y755059D03*
Y1207815D03*
X607874Y302303D03*
Y755059D03*
Y1207815D03*
X732087Y302303D03*
Y755059D03*
Y1207815D03*
X1098524Y-115157D03*
X1281693Y302303D03*
Y755059D03*
Y1207815D03*
X1405906Y302303D03*
Y755059D03*
Y1207815D03*
X1530118Y302303D03*
Y755059D03*
Y1207815D03*
X1654331Y302303D03*
Y755059D03*
Y1207815D03*
X1778543Y302303D03*
Y755059D03*
Y1207815D03*
X1902756Y302303D03*
Y755059D03*
Y1207815D03*
G54D22*
X119763Y550725D03*
Y546225D03*
Y555225D03*
X124263Y546225D03*
Y550725D03*
Y555225D03*
X141978Y958572D03*
X142006Y978425D03*
X209863Y566625D03*
X199102Y969717D03*
Y974717D03*
X183584Y974789D03*
Y969789D03*
X199392Y985113D03*
X183551Y984789D03*
X212063Y976725D03*
X203063D03*
X207563D03*
X216563D03*
X212063Y981725D03*
X216563D03*
X207563D03*
X203063D03*
X199392Y990113D03*
X183551Y989789D03*
X250650Y556997D03*
Y561997D03*
X265545Y556794D03*
Y561794D03*
X250661Y572936D03*
Y577936D03*
X265590Y572801D03*
Y577801D03*
X225563Y976725D03*
X221063D03*
X225563Y981725D03*
X221063D03*
X269763Y569725D03*
X287763D03*
X292263D03*
X274263D03*
X283263D03*
X278763D03*
X283263Y564725D03*
X287763D03*
X292263D03*
X274263D03*
X269763D03*
X278763D03*
X637592Y593186D03*
X641792D03*
Y597386D03*
X637592D03*
X633392Y593186D03*
Y597386D03*
X629192Y593186D03*
Y597386D03*
X641792Y605786D03*
Y601586D03*
X637592D03*
Y605786D03*
X633392D03*
Y601586D03*
X629192D03*
Y605786D03*
X675913Y586555D03*
Y592955D03*
Y598155D03*
X672082Y582834D03*
X666882D03*
X661682D03*
X656482D03*
X695413Y600755D03*
X699613D03*
X669482Y613934D03*
Y609734D03*
X665282D03*
Y613934D03*
X661082D03*
Y609734D03*
X656882Y613934D03*
Y609734D03*
X675913Y603355D03*
X695413Y604955D03*
X691213Y613355D03*
X695413D03*
X699613D03*
X691213Y609155D03*
X695413D03*
X699613Y604955D03*
Y609155D03*
X703813Y592355D03*
Y596555D03*
Y600755D03*
Y613355D03*
Y609155D03*
Y604955D03*
X1370200Y550500D03*
X1366000D03*
X1378100Y530200D03*
Y534400D03*
X1365500Y538600D03*
X1369700D03*
X1365500Y534400D03*
X1369700D03*
X1373900D03*
X1365500Y530200D03*
X1369700D03*
X1373900D03*
X1375900Y568500D03*
X1366000Y563100D03*
X1370200D03*
Y554700D03*
X1366000D03*
X1370200Y558900D03*
X1366000D03*
X1373700Y582900D03*
X1369500D03*
X1377900Y587100D03*
Y591300D03*
Y595500D03*
X1373700D03*
Y591300D03*
Y587100D03*
X1369500Y595500D03*
Y591300D03*
Y587100D03*
X1377900Y599700D03*
X1373700D03*
X1369500D03*
X1396500Y549500D03*
X1386500Y534400D03*
Y530200D03*
X1382300D03*
Y534400D03*
X1396500Y559900D03*
Y554700D03*
Y565100D03*
X1393000Y568500D03*
X1387300D03*
X1381600D03*
X1382100Y587100D03*
X1386300D03*
X1434441Y590424D03*
X1434581Y586136D03*
X1697261Y1004347D03*
X1692761D03*
Y999847D03*
Y995347D03*
X1697261D03*
Y999847D03*
X1783806Y989468D03*
X1862652Y846508D03*
X1850263Y964540D03*
X1850370Y960239D03*
X1845870D03*
X1845763Y964540D03*
Y956040D03*
X1850263D03*
X1825741Y969210D03*
Y974210D03*
X1840683Y969318D03*
Y974318D03*
X1825744Y986011D03*
X1840578Y985885D03*
X1844863Y983125D03*
X1853863D03*
X1858363D03*
X1849363D03*
X1862863D03*
X1853863Y978125D03*
X1844863D03*
X1849363D03*
X1862863D03*
X1858363D03*
X1825744Y991011D03*
X1840578Y990885D03*
X1873099Y817150D03*
X1878099D03*
X1873099Y821650D03*
X1878099D03*
X1873099Y826150D03*
X1878099D03*
X1877512Y831377D03*
X1882512D03*
X1865202Y831559D03*
X1873012Y831377D03*
X1878099Y812650D03*
X1873099D03*
X1878099Y808150D03*
X1873099D03*
X1878099Y803650D03*
X1873099D03*
X1878373Y846472D03*
X1883373D03*
X1867652Y846508D03*
X1867363Y983125D03*
Y978125D03*
G54D19*
X111024Y153681D03*
Y606437D03*
Y1059193D03*
X235236Y153681D03*
Y606437D03*
Y1059193D03*
X359449Y153681D03*
Y606437D03*
Y1059193D03*
X483661Y153681D03*
Y606437D03*
Y1059193D03*
X607874Y153681D03*
Y606437D03*
Y1059193D03*
X732087Y153681D03*
Y606437D03*
Y1059193D03*
X949902Y-115157D03*
X1281693Y153681D03*
Y606437D03*
Y1059193D03*
X1405906Y153681D03*
Y606437D03*
Y1059193D03*
X1530118Y153681D03*
Y606437D03*
Y1059193D03*
X1654331Y153681D03*
Y606437D03*
Y1059193D03*
X1778543Y153681D03*
Y606437D03*
Y1059193D03*
X1902756Y153681D03*
Y606437D03*
Y1059193D03*
G54D37*
X929331Y16536D03*
X937205Y20473D03*
Y12599D03*
Y67717D03*
X929331Y48032D03*
Y32284D03*
X937205Y44095D03*
Y36221D03*
Y28347D03*
X929331Y103150D03*
Y87402D03*
Y71654D03*
X937205Y114961D03*
Y99213D03*
Y83465D03*
X929331Y166142D03*
Y150394D03*
Y134646D03*
Y118898D03*
X937205Y162205D03*
Y146457D03*
Y130709D03*
X929331Y213386D03*
Y197638D03*
Y181890D03*
X937205Y209449D03*
Y193701D03*
Y177953D03*
X929331Y260630D03*
Y244882D03*
Y229134D03*
X937205Y256693D03*
Y240945D03*
Y225197D03*
X929331Y307874D03*
Y292126D03*
Y276378D03*
X937205Y303937D03*
Y288189D03*
Y272441D03*
X929331Y339371D03*
Y323622D03*
X937205Y335434D03*
Y319685D03*
X929331Y395669D03*
X937205Y407480D03*
Y399606D03*
Y391732D03*
X929331Y450787D03*
X937205Y446850D03*
X929331Y427165D03*
Y419291D03*
Y411417D03*
X937205Y431102D03*
Y423228D03*
Y415354D03*
X929331Y498031D03*
Y482283D03*
Y466535D03*
X937205Y494094D03*
Y478346D03*
Y462598D03*
X929331Y545275D03*
Y529527D03*
Y513779D03*
X937205Y541338D03*
Y525590D03*
Y509842D03*
X929331Y592519D03*
Y576771D03*
Y561023D03*
X937205Y588582D03*
Y572834D03*
Y557086D03*
X929331Y639763D03*
Y624015D03*
Y608267D03*
X937205Y635826D03*
Y620078D03*
Y604330D03*
X929331Y687007D03*
Y671259D03*
Y655511D03*
X937205Y683070D03*
Y667322D03*
Y651574D03*
X929331Y718504D03*
Y702755D03*
X937205Y714567D03*
Y698818D03*
X954921Y16536D03*
X947047Y20473D03*
Y12599D03*
X954921Y63780D03*
X947047Y67717D03*
X954921Y40158D03*
Y32284D03*
X947047Y51969D03*
Y44095D03*
Y36221D03*
Y28347D03*
X954921Y111024D03*
Y95276D03*
Y79528D03*
X947047Y107087D03*
Y91339D03*
Y75591D03*
X954921Y158268D03*
Y142520D03*
Y126772D03*
X947047Y154331D03*
Y138583D03*
Y122835D03*
X954921Y205512D03*
Y189764D03*
Y174016D03*
X947047Y201575D03*
Y185827D03*
Y170079D03*
X954921Y252756D03*
Y237008D03*
Y221260D03*
X947047Y248819D03*
Y233071D03*
Y217323D03*
X954921Y300000D03*
Y284252D03*
Y268504D03*
X947047Y296063D03*
Y280315D03*
Y264567D03*
X954921Y339371D03*
Y331496D03*
Y315748D03*
X947047Y327559D03*
Y311811D03*
X954921Y395669D03*
X947047Y407480D03*
Y399606D03*
Y391732D03*
X954921Y442913D03*
X947047Y454724D03*
X954921Y427165D03*
Y419291D03*
Y411417D03*
X947047Y431102D03*
Y423228D03*
X954921Y490157D03*
Y474409D03*
Y458661D03*
X947047Y501968D03*
Y486220D03*
Y470472D03*
X954921Y553149D03*
Y537401D03*
Y521653D03*
Y505905D03*
X947047Y549212D03*
Y533464D03*
Y517716D03*
X954921Y600393D03*
Y584645D03*
Y568897D03*
X947047Y596456D03*
Y580708D03*
Y564960D03*
X954921Y647637D03*
Y631889D03*
Y616141D03*
X947047Y643700D03*
Y627952D03*
Y612204D03*
X954921Y694881D03*
Y679133D03*
Y663385D03*
X947047Y690944D03*
Y675196D03*
Y659448D03*
X954921Y710629D03*
X947047Y706692D03*
X1123031Y16536D03*
X1097441D03*
X1115157Y20473D03*
Y12599D03*
X1105315Y20473D03*
Y12599D03*
X1123031Y63780D03*
X1115157Y67717D03*
X1105315D03*
X1123031Y40158D03*
Y32284D03*
X1097441Y48032D03*
Y32284D03*
X1115157Y51969D03*
Y44095D03*
Y36221D03*
Y28347D03*
X1105315Y44095D03*
Y36221D03*
Y28347D03*
X1123031Y111024D03*
Y95276D03*
Y79528D03*
X1097441Y103150D03*
Y87402D03*
Y71654D03*
X1115157Y107087D03*
Y91339D03*
Y75591D03*
X1105315Y114961D03*
Y99213D03*
Y83465D03*
X1123031Y158268D03*
Y142520D03*
Y126772D03*
X1097441Y166142D03*
Y150394D03*
Y134646D03*
Y118898D03*
X1115157Y154331D03*
Y138583D03*
Y122835D03*
X1105315Y162205D03*
Y146457D03*
Y130709D03*
X1123031Y205512D03*
Y189764D03*
Y174016D03*
X1097441Y213386D03*
Y197638D03*
Y181890D03*
X1115157Y201575D03*
Y185827D03*
Y170079D03*
X1105315Y209449D03*
Y193701D03*
Y177953D03*
X1123031Y252756D03*
Y237008D03*
Y221260D03*
X1097441Y260630D03*
Y244882D03*
Y229134D03*
X1115157Y248819D03*
Y233071D03*
Y217323D03*
X1105315Y256693D03*
Y240945D03*
Y225197D03*
X1123031Y300000D03*
Y284252D03*
Y268504D03*
X1097441Y307874D03*
Y292126D03*
Y276378D03*
X1115157Y296063D03*
Y280315D03*
Y264567D03*
X1105315Y303937D03*
Y288189D03*
Y272441D03*
X1123031Y339371D03*
Y331496D03*
Y315748D03*
X1097441Y339371D03*
Y323622D03*
X1115157Y327559D03*
Y311811D03*
X1105315Y335434D03*
Y319685D03*
X1123031Y395669D03*
X1097441D03*
X1115157Y407480D03*
Y399606D03*
Y391732D03*
X1105315Y407480D03*
Y399606D03*
Y391732D03*
X1123031Y442913D03*
X1097441Y450787D03*
X1115157Y454724D03*
X1105315Y446850D03*
X1123031Y427165D03*
Y419291D03*
Y411417D03*
X1097441Y427165D03*
Y419291D03*
Y411417D03*
X1115157Y431102D03*
Y423228D03*
X1105315Y431102D03*
Y423228D03*
Y415354D03*
X1123031Y490157D03*
Y474409D03*
Y458661D03*
X1097441Y498031D03*
Y482283D03*
Y466535D03*
X1115157Y501968D03*
Y486220D03*
Y470472D03*
X1105315Y494094D03*
Y478346D03*
Y462598D03*
X1123031Y553149D03*
Y537401D03*
Y521653D03*
Y505905D03*
X1097441Y545275D03*
Y529527D03*
Y513779D03*
X1115157Y549212D03*
Y533464D03*
Y517716D03*
X1105315Y541338D03*
Y525590D03*
Y509842D03*
X1123031Y600393D03*
Y584645D03*
Y568897D03*
X1097441Y592519D03*
Y576771D03*
Y561023D03*
X1115157Y596456D03*
Y580708D03*
Y564960D03*
X1105315Y588582D03*
Y572834D03*
Y557086D03*
X1123031Y647637D03*
Y631889D03*
Y616141D03*
X1097441Y639763D03*
Y624015D03*
Y608267D03*
X1115157Y643700D03*
Y627952D03*
Y612204D03*
X1105315Y635826D03*
Y620078D03*
Y604330D03*
X1123031Y694881D03*
Y679133D03*
Y663385D03*
X1097441Y687007D03*
Y671259D03*
Y655511D03*
X1115157Y690944D03*
Y675196D03*
Y659448D03*
X1105315Y683070D03*
Y667322D03*
Y651574D03*
X1123031Y710629D03*
X1097441Y718504D03*
Y702755D03*
X1115157Y706692D03*
X1105315Y714567D03*
Y698818D03*
G54D42*
X974016Y1642401D03*
X986614D03*
X974016Y1636496D03*
Y1648307D03*
X986614Y1636496D03*
Y1648307D03*
X1030709Y1619764D03*
X1014961D03*
X1002362D03*
Y1613858D03*
X1014961D03*
X1030709D03*
X1002362Y1642401D03*
X1014961D03*
X1030709D03*
X1002362Y1625669D03*
Y1636496D03*
Y1648307D03*
X1014961Y1625669D03*
Y1636496D03*
Y1648307D03*
X1030709Y1625669D03*
Y1636496D03*
Y1648307D03*
X1043307Y1619764D03*
Y1613858D03*
Y1642401D03*
Y1625669D03*
Y1636496D03*
Y1648307D03*
X1101457Y1601181D03*
X1119685D03*
X1108150D03*
X1126378D03*
G54D31*
X313312Y98705D03*
X317812Y98905D03*
X385210Y1166347D03*
X450984Y124507D03*
X436811D03*
X479830D03*
X465157D03*
X550197D03*
X536023D03*
X521850D03*
X564370D03*
X753883Y929689D03*
Y937689D03*
Y945689D03*
X756250Y1140250D03*
X838521Y41568D03*
X838043Y37217D03*
X929331Y63780D03*
Y40158D03*
Y24410D03*
X937205Y51969D03*
X929331Y111024D03*
Y95276D03*
Y79528D03*
X937205Y107087D03*
Y91339D03*
Y75591D03*
X929331Y158268D03*
Y142520D03*
Y126772D03*
X937205Y154331D03*
Y138583D03*
Y122835D03*
X929331Y205512D03*
Y189764D03*
Y174016D03*
X937205Y201575D03*
Y185827D03*
Y170079D03*
X929331Y252756D03*
Y237008D03*
Y221260D03*
X937205Y248819D03*
Y233071D03*
Y217323D03*
X929331Y300000D03*
Y284252D03*
Y268504D03*
X937205Y296063D03*
Y280315D03*
Y264567D03*
X929331Y331496D03*
Y315748D03*
X937205Y327559D03*
Y311811D03*
X929331Y403543D03*
Y442913D03*
X937205Y454724D03*
X929331Y490157D03*
Y474409D03*
Y458661D03*
X937205Y501968D03*
Y486220D03*
Y470472D03*
X929331Y553149D03*
Y537401D03*
Y521653D03*
Y505905D03*
X937205Y549212D03*
Y533464D03*
Y517716D03*
X929331Y600393D03*
Y584645D03*
Y568897D03*
X937205Y596456D03*
Y580708D03*
Y564960D03*
X929331Y647637D03*
Y631889D03*
Y616141D03*
X937205Y643700D03*
Y627952D03*
Y612204D03*
X929331Y694881D03*
Y679133D03*
Y663385D03*
X937205Y690944D03*
Y675196D03*
Y659448D03*
X929331Y710629D03*
X937205Y706692D03*
X942925Y1369010D03*
X928384Y1346435D03*
X932559Y1360137D03*
X928439Y1360167D03*
X954921Y48032D03*
Y24410D03*
Y103150D03*
Y87402D03*
Y71654D03*
X947047Y114961D03*
Y99213D03*
Y83465D03*
X954921Y166142D03*
Y150394D03*
Y134646D03*
Y118898D03*
X947047Y162205D03*
Y146457D03*
Y130709D03*
X954921Y213386D03*
Y197638D03*
Y181890D03*
X947047Y209449D03*
Y193701D03*
Y177953D03*
X954921Y260630D03*
Y244882D03*
Y229134D03*
X947047Y256693D03*
Y240945D03*
Y225197D03*
X954921Y307874D03*
Y292126D03*
Y276378D03*
X947047Y303937D03*
Y288189D03*
Y272441D03*
X954921Y323622D03*
X947047Y335434D03*
Y319685D03*
X954921Y403543D03*
Y450787D03*
X947047Y446850D03*
Y415354D03*
X954921Y498031D03*
Y482283D03*
Y466535D03*
X947047Y494094D03*
Y478346D03*
Y462598D03*
X954921Y545275D03*
Y529527D03*
Y513779D03*
X947047Y541338D03*
Y525590D03*
Y509842D03*
X954921Y592519D03*
Y576771D03*
Y561023D03*
X947047Y588582D03*
Y572834D03*
Y557086D03*
X954921Y639763D03*
Y624015D03*
Y608267D03*
X947047Y635826D03*
Y620078D03*
Y604330D03*
X954921Y687007D03*
Y671259D03*
Y655511D03*
X947047Y683070D03*
Y667322D03*
Y651574D03*
X954921Y718504D03*
Y702755D03*
X947047Y714567D03*
Y698818D03*
X947125Y1369010D03*
X1034916Y-82413D03*
Y-87913D03*
X1011984Y-83066D03*
X1012174Y-88726D03*
X1050100Y392600D03*
Y397600D03*
Y402600D03*
X1044600Y392500D03*
Y397500D03*
Y402500D03*
Y407500D03*
X1050100Y407600D03*
X1044680Y921400D03*
X1097441Y63780D03*
X1123031Y48032D03*
Y24410D03*
X1097441Y40158D03*
Y24410D03*
X1105315Y51969D03*
X1123031Y103150D03*
Y87402D03*
Y71654D03*
X1097441Y111024D03*
Y95276D03*
Y79528D03*
X1115157Y114961D03*
Y99213D03*
Y83465D03*
X1105315Y107087D03*
Y91339D03*
Y75591D03*
X1123031Y166142D03*
Y150394D03*
Y134646D03*
Y118898D03*
X1097441Y158268D03*
Y142520D03*
Y126772D03*
X1115157Y162205D03*
Y146457D03*
Y130709D03*
X1105315Y154331D03*
Y138583D03*
Y122835D03*
X1123031Y213386D03*
Y197638D03*
Y181890D03*
X1097441Y205512D03*
Y189764D03*
Y174016D03*
X1115157Y209449D03*
Y193701D03*
Y177953D03*
X1105315Y201575D03*
Y185827D03*
Y170079D03*
X1123031Y260630D03*
Y244882D03*
Y229134D03*
X1097441Y252756D03*
Y237008D03*
Y221260D03*
X1115157Y256693D03*
Y240945D03*
Y225197D03*
X1105315Y248819D03*
Y233071D03*
Y217323D03*
X1123031Y307874D03*
Y292126D03*
Y276378D03*
X1097441Y300000D03*
Y284252D03*
Y268504D03*
X1115157Y303937D03*
Y288189D03*
Y272441D03*
X1105315Y296063D03*
Y280315D03*
Y264567D03*
X1123031Y323622D03*
X1097441Y331496D03*
Y315748D03*
X1115157Y335434D03*
Y319685D03*
X1105315Y327559D03*
Y311811D03*
X1123031Y403543D03*
X1097441D03*
X1123031Y450787D03*
X1097441Y442913D03*
X1115157Y446850D03*
X1105315Y454724D03*
X1115157Y415354D03*
X1123031Y498031D03*
Y482283D03*
Y466535D03*
X1097441Y490157D03*
Y474409D03*
Y458661D03*
X1115157Y494094D03*
Y478346D03*
Y462598D03*
X1105315Y501968D03*
Y486220D03*
Y470472D03*
X1123031Y545275D03*
Y529527D03*
Y513779D03*
X1097441Y553149D03*
Y537401D03*
Y521653D03*
Y505905D03*
X1115157Y541338D03*
Y525590D03*
Y509842D03*
X1105315Y549212D03*
Y533464D03*
Y517716D03*
X1123031Y592519D03*
Y576771D03*
Y561023D03*
X1097441Y600393D03*
Y584645D03*
Y568897D03*
X1115157Y588582D03*
Y572834D03*
Y557086D03*
X1105315Y596456D03*
Y580708D03*
Y564960D03*
X1123031Y639763D03*
Y624015D03*
Y608267D03*
X1097441Y647637D03*
Y631889D03*
Y616141D03*
X1115157Y635826D03*
Y620078D03*
Y604330D03*
X1105315Y643700D03*
Y627952D03*
Y612204D03*
X1123031Y687007D03*
Y671259D03*
Y655511D03*
X1097441Y694881D03*
Y679133D03*
Y663385D03*
X1115157Y683070D03*
Y667322D03*
Y651574D03*
X1105315Y690944D03*
Y675196D03*
Y659448D03*
X1123031Y718504D03*
Y702755D03*
X1097441Y710629D03*
X1115157Y714567D03*
Y698818D03*
X1105315Y706692D03*
X1119159Y878130D03*
Y873130D03*
Y868130D03*
X1116159Y870630D03*
Y875630D03*
X1259800Y631998D03*
Y619498D03*
Y1072254D03*
Y1084754D03*
X1413400Y575000D03*
X1384013Y631998D03*
Y619498D03*
Y1072254D03*
Y1084754D03*
X1447834Y124507D03*
X1504527D03*
X1490354D03*
X1518701D03*
X1508225Y631998D03*
Y619498D03*
Y1072254D03*
Y1084754D03*
X1532874Y124507D03*
X1632438Y179242D03*
Y166742D03*
Y631998D03*
Y619498D03*
Y1072254D03*
Y1084754D03*
X1756650Y179242D03*
Y166742D03*
X1731650Y631998D03*
Y619498D03*
X1756650Y1072254D03*
Y1084754D03*
X1880863Y179242D03*
Y166742D03*
Y631998D03*
Y619498D03*
Y1072254D03*
X1884835Y1067400D03*
X1880863Y1084754D03*
G54D11*
X24508Y5500D03*
X20000Y60000D03*
X5500Y61492D03*
Y56492D03*
Y51492D03*
Y46492D03*
Y41492D03*
Y66492D03*
X20000Y80000D03*
Y100000D03*
X5500Y81492D03*
Y76492D03*
Y96492D03*
Y91492D03*
Y86492D03*
Y71492D03*
Y101492D03*
Y111492D03*
Y116492D03*
Y106492D03*
X20000Y120000D03*
Y140000D03*
Y160000D03*
X5500Y126492D03*
Y121492D03*
Y141492D03*
Y151492D03*
Y161492D03*
Y156492D03*
Y146492D03*
Y131492D03*
Y136492D03*
X20000Y180000D03*
Y200000D03*
X5500Y181492D03*
Y191492D03*
Y201492D03*
Y211492D03*
Y171492D03*
Y206492D03*
Y196492D03*
Y176492D03*
Y166492D03*
Y186492D03*
X20000Y220000D03*
Y240000D03*
Y260000D03*
X5500Y231492D03*
Y241492D03*
Y251492D03*
Y261492D03*
Y221492D03*
Y256492D03*
Y246492D03*
Y226492D03*
Y216492D03*
Y236492D03*
X20000Y280000D03*
Y300000D03*
X5500Y281492D03*
Y291492D03*
Y301492D03*
Y271492D03*
Y306492D03*
Y296492D03*
Y286492D03*
Y276492D03*
Y266492D03*
X20000Y320000D03*
Y340000D03*
X5500Y331492D03*
Y341492D03*
Y351492D03*
Y311492D03*
Y321492D03*
Y356492D03*
Y346492D03*
Y336492D03*
Y326492D03*
Y316492D03*
X20000Y360000D03*
Y380000D03*
Y400000D03*
X5500Y381492D03*
Y391492D03*
Y401492D03*
Y361492D03*
Y371492D03*
Y406492D03*
Y396492D03*
Y386492D03*
Y376492D03*
Y366492D03*
X20000Y420000D03*
Y440000D03*
X5500Y451492D03*
Y441492D03*
Y431492D03*
Y421492D03*
Y411492D03*
Y416492D03*
Y436492D03*
Y446492D03*
Y426492D03*
Y501492D03*
Y456492D03*
Y496492D03*
Y531492D03*
Y551492D03*
Y541492D03*
Y521492D03*
Y511492D03*
Y536492D03*
Y546492D03*
Y506492D03*
Y516492D03*
Y526492D03*
Y581492D03*
Y591492D03*
Y571492D03*
Y561492D03*
Y586492D03*
Y596492D03*
Y556492D03*
Y566492D03*
Y576492D03*
Y631492D03*
Y641492D03*
Y621492D03*
Y611492D03*
Y601492D03*
Y636492D03*
Y646492D03*
Y606492D03*
Y616492D03*
Y626492D03*
Y681492D03*
Y691492D03*
Y671492D03*
Y661492D03*
Y651492D03*
Y686492D03*
Y696492D03*
Y656492D03*
Y666492D03*
Y676492D03*
Y731492D03*
Y741492D03*
Y721492D03*
Y711492D03*
Y701492D03*
Y736492D03*
Y706492D03*
Y716492D03*
Y726492D03*
Y781492D03*
Y791492D03*
Y771492D03*
Y761492D03*
Y751492D03*
Y786492D03*
Y746492D03*
Y756492D03*
Y766492D03*
Y776492D03*
Y831492D03*
Y841492D03*
Y821492D03*
Y811492D03*
Y801492D03*
Y836492D03*
Y796492D03*
Y806492D03*
Y816492D03*
Y826492D03*
Y881492D03*
Y871492D03*
Y861492D03*
Y851492D03*
Y886492D03*
Y846492D03*
Y856492D03*
Y866492D03*
Y876492D03*
X15000Y930000D03*
Y920000D03*
X25000Y930000D03*
Y920000D03*
X5500Y931492D03*
Y921492D03*
Y911492D03*
Y901492D03*
Y891492D03*
Y936492D03*
Y896492D03*
Y906492D03*
Y916492D03*
Y926492D03*
X15000Y980000D03*
Y970000D03*
Y960000D03*
Y950000D03*
Y940000D03*
X25000D03*
Y950000D03*
Y960000D03*
Y970000D03*
Y980000D03*
X5500Y976492D03*
Y981492D03*
Y986492D03*
Y966492D03*
Y956492D03*
Y961492D03*
Y971492D03*
Y951492D03*
Y941492D03*
Y946492D03*
X15000Y1030000D03*
Y1020000D03*
Y1010000D03*
Y1000000D03*
Y990000D03*
X25000D03*
Y1000000D03*
Y1010000D03*
Y1020000D03*
X5500Y991492D03*
Y996492D03*
Y1001492D03*
Y1006492D03*
Y1026492D03*
Y1016492D03*
Y1011492D03*
Y1021492D03*
Y1031492D03*
X25000Y1040000D03*
Y1080000D03*
Y1070000D03*
Y1060000D03*
Y1050000D03*
X5500Y1036492D03*
Y1066492D03*
Y1056492D03*
Y1046492D03*
Y1041492D03*
Y1051492D03*
Y1061492D03*
Y1071492D03*
Y1081492D03*
Y1076492D03*
X25000Y1090000D03*
X5500Y1121492D03*
Y1131492D03*
Y1111492D03*
Y1101492D03*
Y1091492D03*
Y1086492D03*
Y1096492D03*
Y1106492D03*
Y1116492D03*
Y1126492D03*
Y1171492D03*
Y1161492D03*
Y1151492D03*
Y1141492D03*
Y1136492D03*
Y1146492D03*
Y1156492D03*
Y1166492D03*
Y1176492D03*
Y1221492D03*
Y1211492D03*
Y1201492D03*
Y1191492D03*
Y1181492D03*
Y1186492D03*
Y1196492D03*
Y1206492D03*
Y1216492D03*
Y1226492D03*
X17500Y1270000D03*
Y1260000D03*
Y1250000D03*
Y1240000D03*
X5500Y1271492D03*
Y1261492D03*
Y1251492D03*
Y1241492D03*
Y1231492D03*
Y1236492D03*
Y1246492D03*
Y1256492D03*
Y1266492D03*
Y1276492D03*
X17500Y1290000D03*
Y1280000D03*
Y1300000D03*
Y1310000D03*
X5500Y1321492D03*
Y1311492D03*
Y1301492D03*
Y1291492D03*
Y1281492D03*
Y1286492D03*
Y1296492D03*
Y1306492D03*
Y1316492D03*
X17500Y1320000D03*
Y1360000D03*
Y1350000D03*
Y1330000D03*
Y1340000D03*
X8983Y1368303D03*
X13983D03*
X18983D03*
X23983D03*
X5500Y1361492D03*
Y1351492D03*
Y1341492D03*
Y1331492D03*
Y1336492D03*
Y1346492D03*
Y1356492D03*
Y1326492D03*
X60000Y20000D03*
X29508Y5500D03*
X39508D03*
X34508D03*
X44508D03*
X64508D03*
X69508D03*
X54508D03*
X49508D03*
X59508D03*
X60000Y40000D03*
X40000D03*
X60000Y60000D03*
X40000D03*
Y80000D03*
X60000D03*
Y100000D03*
X40000D03*
X60000Y120000D03*
X40000D03*
Y140000D03*
X60000D03*
Y160000D03*
X40000D03*
X38500Y202000D03*
X64487Y212761D03*
X56000Y237000D03*
X73437Y247161D03*
X49437Y254661D03*
X73437Y234661D03*
X62000Y276500D03*
X40000Y280000D03*
Y300000D03*
X60000D03*
Y320000D03*
X40000D03*
X60000Y340000D03*
X40000D03*
Y360000D03*
X35000Y446500D03*
X50500Y545500D03*
X58346Y516473D03*
X54088Y512336D03*
X39853Y512373D03*
X44111Y516510D03*
X40000Y560000D03*
Y580000D03*
Y600000D03*
Y620000D03*
X39000Y646000D03*
X30697Y679553D03*
X73437Y687417D03*
X64487Y665417D03*
X31043Y689115D03*
X30676Y663764D03*
X49500Y729000D03*
X49437Y707417D03*
X73437Y699917D03*
X31064Y704904D03*
X69500Y777000D03*
X51000Y755500D03*
X38500Y800500D03*
X39000Y834500D03*
X49000Y811000D03*
X51000Y846000D03*
X40000Y930000D03*
Y920000D03*
Y970000D03*
Y960000D03*
Y950000D03*
Y940000D03*
X50000Y1030000D03*
X70000Y1020000D03*
X40000Y1000000D03*
Y990000D03*
X50000Y1060000D03*
X64487Y1118173D03*
X30256Y1116731D03*
X30670Y1132472D03*
X30644Y1157871D03*
X49437Y1160173D03*
X73437Y1140173D03*
Y1152673D03*
X30623Y1142082D03*
X52000Y1186000D03*
X71500Y1205000D03*
X45800Y1306100D03*
X37500Y1360000D03*
X27500D03*
X28983Y1368303D03*
X33983D03*
X38983D03*
X43983D03*
X48983D03*
X53983D03*
X58983D03*
X63983D03*
X68983D03*
X114508Y5500D03*
X119508D03*
X104508D03*
X94508D03*
X84508D03*
X74508D03*
X79508D03*
X89508D03*
X99508D03*
X109508D03*
X80000Y80000D03*
X100000D03*
X120000D03*
Y100000D03*
X100000D03*
X80000D03*
X120000Y120000D03*
X100000D03*
X80000D03*
X86500Y157500D03*
X80000Y140000D03*
X118437Y141870D03*
X78500Y169500D03*
X111437Y195492D03*
X106937Y198543D03*
Y207992D03*
X111437Y165492D03*
Y180492D03*
X74937Y187461D03*
X92287Y194661D03*
X86637Y194861D03*
X82000Y219000D03*
X111437Y245492D03*
Y235492D03*
X106937Y217441D03*
X111437Y265492D03*
Y275492D03*
X89237Y276861D03*
X95437Y300161D03*
X96000Y336500D03*
X80000Y320000D03*
Y340000D03*
X118437Y314114D03*
X89000Y403500D03*
X100000Y420000D03*
X120000Y440000D03*
X100000D03*
Y460000D03*
X120000D03*
Y480000D03*
X100000D03*
X120000Y500000D03*
X100000D03*
X104500Y515500D03*
X120500Y524000D03*
X86500Y522000D03*
X100000Y541500D03*
X87000Y541000D03*
X89000Y557500D03*
X108500Y572000D03*
X88000Y577500D03*
X118753Y594626D03*
X88000Y602500D03*
X111437Y648248D03*
Y633248D03*
Y618248D03*
X92287Y647417D03*
X86637Y647617D03*
X74937Y640217D03*
X81500Y672000D03*
X106937Y670197D03*
X111437Y688248D03*
X106937Y660748D03*
Y651299D03*
X111437Y728248D03*
Y718248D03*
Y698248D03*
X89237Y729617D03*
X75500Y757500D03*
X94000Y789000D03*
X118437Y766870D03*
X95437Y752917D03*
X89500Y802500D03*
X90000Y858000D03*
X100000Y880000D03*
Y900000D03*
X120000D03*
Y920000D03*
X100000D03*
X120000Y940000D03*
X83100Y984800D03*
X78600D03*
X83100Y980300D03*
X78600D03*
X100000Y940000D03*
X120000Y1025000D03*
X85000Y1020000D03*
X78600Y989300D03*
X83100D03*
X74000Y1074000D03*
X85000Y1060000D03*
X111437Y1071004D03*
X118437Y1047382D03*
X81000Y1124500D03*
X106937Y1122953D03*
Y1113504D03*
Y1104055D03*
X111437Y1101004D03*
Y1086004D03*
X92287Y1100173D03*
X86637Y1100373D03*
X74937Y1092973D03*
X111437Y1171004D03*
Y1151004D03*
Y1141004D03*
X118437Y1219626D03*
X111437Y1181004D03*
X89237Y1182373D03*
X95437Y1205673D03*
X98500Y1241000D03*
X90000Y1252500D03*
X86000Y1282000D03*
X93000Y1319000D03*
X73983Y1368303D03*
X78983D03*
X83983D03*
X88983D03*
X93983D03*
X98983D03*
X107374Y1369303D03*
X112374D03*
X117374D03*
X160000Y20000D03*
X134508Y5500D03*
X124508D03*
X129508D03*
X169508D03*
X159508D03*
X149508D03*
X139508D03*
X154508D03*
X164508D03*
X144508D03*
X160000Y60000D03*
Y40000D03*
X140000D03*
Y60000D03*
X160000Y100000D03*
Y80000D03*
X140000D03*
Y100000D03*
X160000Y140000D03*
X140000D03*
X160000Y120000D03*
X140000D03*
X156500Y170500D03*
X130500Y211500D03*
X160500Y190000D03*
X160000Y180000D03*
X129000Y259000D03*
X142687Y237161D03*
X128000Y288500D03*
X160000Y280000D03*
X140000Y300000D03*
X160000D03*
X140000Y320000D03*
X160000D03*
X140000Y440000D03*
Y460000D03*
Y480000D03*
Y500000D03*
X142500Y515500D03*
X150000Y526500D03*
X164107Y512331D03*
X168365Y516368D03*
X135000Y588000D03*
X167000Y613000D03*
X147500Y605500D03*
X142687Y689917D03*
X135200Y738400D03*
X153705Y744831D03*
X153714Y720741D03*
X153757Y710653D03*
X140372Y732370D03*
X160000Y880000D03*
Y900000D03*
X140000Y920000D03*
X160000D03*
Y940000D03*
X140000D03*
X156000Y1032000D03*
X134000Y1064000D03*
X153000Y1105000D03*
X132000Y1117000D03*
X142687Y1142673D03*
X154363Y1161725D03*
X153716Y1174793D03*
X170000Y1190500D03*
X153824Y1197248D03*
X153932Y1182940D03*
X122374Y1369303D03*
X127374D03*
X132374D03*
X137374D03*
X142374D03*
X147374D03*
X152374D03*
X157374D03*
X162374D03*
X167374D03*
X200000Y20000D03*
X180000D03*
X209508Y5500D03*
X199508D03*
X189508D03*
X179508D03*
X204508D03*
X214508D03*
X174508D03*
X184508D03*
X194508D03*
X200000Y40000D03*
X180000D03*
X200000Y60000D03*
X180000D03*
Y80000D03*
X200000D03*
Y100000D03*
X180000D03*
Y120000D03*
X200000D03*
Y140000D03*
X180000D03*
X216500Y194756D03*
X210849Y194861D03*
X199149Y187461D03*
X188699Y212561D03*
X206000Y219000D03*
X180500Y237000D03*
X197649Y234661D03*
X173649Y254661D03*
X197649Y247161D03*
X180000Y300000D03*
X213449Y276861D03*
X180000Y320000D03*
Y340000D03*
X200000D03*
X178342Y512294D03*
X182600Y516331D03*
X210000Y644000D03*
X216499Y636917D03*
X199149Y631217D03*
X210849Y638617D03*
X206000Y672000D03*
X197649Y687417D03*
X213449Y729617D03*
X173649Y707417D03*
X197649Y699917D03*
X180000Y860000D03*
Y880000D03*
Y920000D03*
Y900000D03*
X215563Y1001225D03*
X203563D03*
X207563D03*
X211563D03*
X211000Y1065000D03*
X203500Y1124500D03*
X216499Y1100173D03*
X210849Y1100373D03*
X199149Y1092973D03*
X188399Y1113873D03*
X175000Y1143000D03*
X173649Y1160173D03*
X193423Y1140945D03*
X197649Y1152673D03*
X213449Y1182373D03*
X181000Y1261000D03*
X190000Y1320000D03*
X200000D03*
X210000D03*
Y1300000D03*
Y1310000D03*
X200000D03*
X190000D03*
X172374Y1369303D03*
X177374D03*
X182374D03*
X187374D03*
X192374D03*
X197374D03*
X202374D03*
X207374D03*
X212374D03*
X217374D03*
X260000Y20000D03*
X220000D03*
X240000D03*
X259508Y5500D03*
X249508D03*
X239508D03*
X229508D03*
X219508D03*
X224508D03*
X234508D03*
X244508D03*
X254508D03*
X264508D03*
X260000Y60000D03*
Y40000D03*
X240000D03*
X220000D03*
Y60000D03*
X240000D03*
X260000Y100000D03*
Y80000D03*
X240000D03*
X220000D03*
Y100000D03*
X240000D03*
X260000Y140000D03*
Y120000D03*
X240000D03*
X220000D03*
X242649Y141870D03*
X262000Y209000D03*
X235649Y195492D03*
X231991Y198543D03*
X231149Y207992D03*
X235649Y165492D03*
Y180492D03*
X253000Y260000D03*
X266899Y237161D03*
X235649Y245492D03*
Y235492D03*
X231149Y217441D03*
X255000Y280000D03*
X235649Y265492D03*
Y275492D03*
X219649Y300161D03*
X242649Y314114D03*
X220000Y360000D03*
X240000Y380000D03*
X220000D03*
Y400000D03*
X240000D03*
Y420000D03*
X220000D03*
Y440000D03*
X240000D03*
Y460000D03*
X220000D03*
Y480000D03*
X240000D03*
Y500000D03*
X220000D03*
Y520000D03*
X243051Y594626D03*
X235649Y648248D03*
Y633248D03*
Y618248D03*
X255500Y664500D03*
X231149Y670197D03*
X235649Y688248D03*
X231149Y660748D03*
Y651299D03*
X266899Y689917D03*
X235649Y728248D03*
Y718248D03*
Y698248D03*
X264739Y732114D03*
X242649Y766870D03*
X219649Y752917D03*
X248500Y788500D03*
X225000Y840000D03*
X245000D03*
X265000Y795000D03*
X225000Y815000D03*
Y880000D03*
X245000D03*
X225000Y860000D03*
X245000D03*
X225000Y900000D03*
X245000D03*
Y940000D03*
X263000Y1023000D03*
X219563Y1001225D03*
X223563D03*
X263000Y1047000D03*
X235649Y1071004D03*
X242649Y1047382D03*
X231149Y1122953D03*
Y1113504D03*
Y1104055D03*
X235649Y1101004D03*
Y1086004D03*
Y1171004D03*
Y1151004D03*
X235300Y1142700D03*
X266899Y1141173D03*
X255000Y1207500D03*
X242649Y1219626D03*
X235649Y1181004D03*
X219649Y1205673D03*
X257000Y1253000D03*
X220000Y1270000D03*
Y1320000D03*
X230000D03*
X240000D03*
X250000D03*
X260000D03*
X220000Y1280000D03*
X230000D03*
X250000Y1290000D03*
X240000D03*
X230000D03*
X220000D03*
Y1300000D03*
X230000D03*
X240000D03*
X250000D03*
X260000D03*
Y1310000D03*
X250000D03*
X240000D03*
X230000D03*
X220000D03*
X222374Y1369303D03*
X227374D03*
X232374D03*
X237374D03*
X242374D03*
X247374D03*
X252374D03*
X257374D03*
X262374D03*
X300000Y20000D03*
X280000D03*
X309508Y5500D03*
X299508D03*
X289508D03*
X279508D03*
X269508D03*
X304508D03*
X314508D03*
X274508D03*
X284508D03*
X294508D03*
X300000Y40000D03*
X280000Y60000D03*
Y40000D03*
Y100000D03*
Y80000D03*
X312355Y72855D03*
X280000Y140000D03*
Y120000D03*
X270000Y179500D03*
X285500Y189500D03*
X283000Y181000D03*
X314329Y212420D03*
X304500Y237000D03*
X297862Y254661D03*
X300000Y300000D03*
Y320000D03*
Y340000D03*
X295000Y400000D03*
Y440000D03*
Y460000D03*
X302513Y512294D03*
X306771Y516331D03*
X292536Y516368D03*
X288278Y512331D03*
X282263Y589225D03*
X270263D03*
X274263D03*
X286263D03*
X290263D03*
X278263D03*
X277000Y618500D03*
X275000Y647000D03*
X294500Y607500D03*
X284000D03*
X312912Y665417D03*
X277972Y744575D03*
X297862Y707417D03*
X277981Y720485D03*
X278024Y710397D03*
X286000Y810500D03*
X305200Y1068400D03*
X295200Y1078400D03*
Y1058400D03*
X281000Y1105000D03*
X312912Y1118273D03*
X304500Y1142500D03*
X302452Y1165162D03*
X278577Y1161725D03*
X277930Y1175001D03*
X306000Y1182500D03*
X278076Y1197355D03*
X278146Y1182940D03*
X301000Y1231000D03*
X267374Y1369303D03*
X272374D03*
X277374D03*
X282374D03*
X287374D03*
X292374D03*
X297374D03*
X302374D03*
X307374D03*
X312374D03*
X360000Y20000D03*
X340000D03*
X320000D03*
X359508Y5500D03*
X349508D03*
X339508D03*
X329508D03*
X319508D03*
X324508D03*
X334508D03*
X344508D03*
X354508D03*
X360000Y40000D03*
X340000D03*
X320000D03*
X355200Y58400D03*
X346245Y58745D03*
X353001Y81799D03*
X351000Y70700D03*
X328000Y150500D03*
X333021Y129679D03*
X359862Y165492D03*
Y180492D03*
Y195492D03*
X355362Y198543D03*
Y207992D03*
X323362Y187461D03*
X340712Y194661D03*
X335062Y194861D03*
X333500Y219000D03*
X359862Y245492D03*
Y235492D03*
X355362Y217441D03*
X321862Y234661D03*
Y247161D03*
X359862Y265492D03*
Y275492D03*
X337662Y276861D03*
X343862Y300161D03*
X352000Y331000D03*
X320000Y340000D03*
X350000Y440000D03*
X330000D03*
X350000Y500000D03*
Y480000D03*
Y460000D03*
X330000D03*
Y540000D03*
X350000D03*
Y520000D03*
X333000Y560000D03*
Y580000D03*
X350000Y560000D03*
X333000Y604000D03*
X359862Y648248D03*
Y633248D03*
Y618248D03*
X340712Y647517D03*
X335062Y647617D03*
X323362Y640217D03*
X330000Y672000D03*
X355362Y670197D03*
X359862Y688248D03*
X355362Y660748D03*
Y651299D03*
X321862Y687417D03*
X359862Y728248D03*
Y718248D03*
Y698248D03*
X337662Y729617D03*
X321862Y699917D03*
X355000Y780500D03*
X320000Y750000D03*
X330000Y770000D03*
X347000Y788500D03*
X343862Y752917D03*
X361500Y901500D03*
X330000Y900000D03*
X360000Y960000D03*
Y940000D03*
X330000Y960000D03*
X322000Y988500D03*
X362000Y1017000D03*
X328000Y1061000D03*
X359862Y1071004D03*
X355362Y1122953D03*
Y1113504D03*
Y1104055D03*
X359862Y1101004D03*
Y1086004D03*
X340812Y1100273D03*
X335062Y1100373D03*
X323362Y1092973D03*
X358518Y1171114D03*
X359862Y1151004D03*
Y1141004D03*
X321862Y1140173D03*
Y1152673D03*
X327500Y1197000D03*
X359862Y1181004D03*
X337662Y1182373D03*
X343862Y1205673D03*
X353000Y1231000D03*
X330000Y1302000D03*
X333983Y1368303D03*
X338983D03*
X343983D03*
X348983D03*
X353983D03*
X358983D03*
X363983D03*
X317374Y1369303D03*
X322374D03*
X327374D03*
X380000Y20000D03*
X395075Y18639D03*
Y13639D03*
X389508Y5500D03*
X379508D03*
X369508D03*
X364508D03*
X374508D03*
X384508D03*
X394508D03*
X380000Y60000D03*
Y40000D03*
X395075Y43639D03*
Y38639D03*
Y33639D03*
Y28639D03*
Y23639D03*
X399000Y62000D03*
X396000Y55500D03*
X396075Y50248D03*
X401000Y89000D03*
X400000Y80000D03*
X365162Y88731D03*
Y77731D03*
X388500Y153500D03*
X395500Y160500D03*
X366862Y141870D03*
X386000Y209000D03*
X390312Y237161D03*
X389000Y289000D03*
X385500Y313000D03*
X366862Y314114D03*
X390000Y500000D03*
X370000D03*
X390000Y540000D03*
Y520000D03*
X370000D03*
Y540000D03*
X389000Y594500D03*
X390000Y560000D03*
X370000D03*
X366862Y594626D03*
X395000Y631000D03*
X388000Y607000D03*
X410000Y692500D03*
X379000Y664000D03*
X391112Y689917D03*
X402129Y744503D03*
X388796Y732042D03*
X402138Y720413D03*
X402181Y710325D03*
X402500Y780500D03*
X366862Y766870D03*
X397000Y911000D03*
X380000Y960000D03*
Y940000D03*
X393500Y988500D03*
Y1017000D03*
X390000Y1055000D03*
X366862Y1047382D03*
X391112Y1142673D03*
X399474Y1166787D03*
X366862Y1219626D03*
X406037Y1192706D03*
X402403Y1188312D03*
X368983Y1368303D03*
X373983D03*
X378983D03*
X383983D03*
X388983D03*
X393983D03*
X398983D03*
X403983D03*
X408983D03*
X437124Y212661D03*
X447574Y187461D03*
X446074Y247161D03*
X422300Y254661D03*
X446074Y234661D03*
X430000Y545500D03*
X460000Y540000D03*
X426663Y512257D03*
X430921Y516294D03*
X416686Y516331D03*
X412428Y512294D03*
X460000Y600000D03*
X445000D03*
X440000Y560000D03*
X460000D03*
X440000Y613000D03*
X459274Y647617D03*
X447574Y640217D03*
X417000Y652500D03*
X454500Y672000D03*
X446074Y687417D03*
X437224Y665417D03*
X452500Y744500D03*
X437500Y744000D03*
X422074Y707417D03*
X446074Y699917D03*
X455000Y780000D03*
X445000D03*
X440000Y760000D03*
X445000Y798000D03*
X428000Y988500D03*
X424000Y1105000D03*
X418500Y1176800D03*
X437104Y1160696D03*
X450500Y1208500D03*
X424000Y1206000D03*
X454500Y1248500D03*
X460000Y1320000D03*
X440000D03*
X460000Y1300000D03*
X413983Y1368303D03*
X418983D03*
X423983D03*
X428983D03*
X433983D03*
X438983D03*
X443983D03*
X448983D03*
X453983D03*
X458983D03*
X476319Y144481D03*
X506750Y165324D03*
X480159Y201245D03*
X500184Y200328D03*
X497785Y178034D03*
X478306Y195593D03*
X461122Y194861D03*
X484074Y245492D03*
X478651Y220734D03*
X484074Y235492D03*
Y275492D03*
X481174Y265492D03*
X461874Y276861D03*
X468074Y300161D03*
X491074Y314114D03*
X470000Y400000D03*
Y380000D03*
Y430000D03*
X465000Y491000D03*
X506746Y512331D03*
X499000Y553000D03*
X491074Y594626D03*
X484074Y648248D03*
Y633248D03*
Y618248D03*
X464924Y647417D03*
X479574Y670197D03*
X484074Y688248D03*
X479574Y660748D03*
Y651299D03*
X484074Y728248D03*
Y718248D03*
Y698248D03*
X461874Y729617D03*
X461500Y769500D03*
X491074Y766870D03*
X468074Y752917D03*
X500000Y960000D03*
Y940000D03*
X480000Y960000D03*
Y940000D03*
X504000Y988500D03*
X462000D03*
X468000Y1047000D03*
X484074Y1071004D03*
X491074Y1047382D03*
X479574Y1113504D03*
Y1104055D03*
X484074Y1101004D03*
Y1086004D03*
X504724Y1118073D03*
X484074Y1171004D03*
Y1151004D03*
Y1141004D03*
X506700Y1141973D03*
X502500Y1211500D03*
X476373Y1219498D03*
X484074Y1181004D03*
X461874Y1182373D03*
X468074Y1205673D03*
X480000Y1320000D03*
X500000Y1300000D03*
X480000D03*
Y1280000D03*
X463983Y1368303D03*
X468983D03*
X473983D03*
X478983D03*
X483983D03*
X488983D03*
X493983D03*
X498983D03*
X503983D03*
X508983D03*
X519868Y242334D03*
X515500Y301000D03*
X550987Y262810D03*
X548500Y343000D03*
X515000Y322500D03*
X547500Y440000D03*
X520981Y512294D03*
X525239Y516331D03*
X511004Y516368D03*
X540000Y583000D03*
Y600000D03*
X520000D03*
X528000Y611000D03*
X532000Y623000D03*
X515324Y689917D03*
X526225Y744756D03*
X546287Y707417D03*
X512892Y732295D03*
X526277Y710578D03*
X526234Y720666D03*
X509000Y772000D03*
X555500Y852000D03*
X551500Y888000D03*
X523500Y883500D03*
X525000Y937000D03*
X525500Y967000D03*
X523000Y1045000D03*
X528500Y1073500D03*
X546287Y1160173D03*
X535320Y1152771D03*
X534874Y1139774D03*
X526523Y1177122D03*
X526501Y1166546D03*
X526388Y1197747D03*
X526367Y1183111D03*
X539000Y1309000D03*
X517374Y1369303D03*
X522374D03*
X527374D03*
X532374D03*
X537374D03*
X542374D03*
X547374D03*
X552374D03*
X557374D03*
X597051Y7699D03*
Y12699D03*
Y17699D03*
X604146Y5500D03*
X597051Y22699D03*
Y27699D03*
Y32699D03*
Y37699D03*
Y42699D03*
X589000Y64000D03*
X594000Y61500D03*
X596000Y56500D03*
X596051Y51090D03*
X603787Y207992D03*
X604517Y196263D03*
X603697Y182091D03*
X586719Y196888D03*
X568687Y187660D03*
X583487Y194861D03*
X588188Y216520D03*
X570287Y234661D03*
X563000Y217600D03*
X569009Y247887D03*
X592287Y300161D03*
X582758Y276861D03*
X590000Y342000D03*
X560000Y438500D03*
X594500Y462000D03*
X569529Y502127D03*
X592000Y595000D03*
X580000Y600000D03*
X560000D03*
X586000Y611000D03*
X589137Y647417D03*
X583487Y647617D03*
X571787Y640217D03*
X579000Y672000D03*
X603787Y670197D03*
Y660748D03*
Y651299D03*
X570287Y687417D03*
X561437Y665417D03*
X559000Y741000D03*
X586087Y729617D03*
X570287Y699917D03*
X603000Y781000D03*
X592287Y752917D03*
X604000Y897000D03*
X592000Y900500D03*
X589500Y988000D03*
X571000D03*
X575000Y1057500D03*
X586500Y1061500D03*
X586000Y1046500D03*
X575000Y1046000D03*
X561337Y1120873D03*
X583487Y1100373D03*
X571787Y1092973D03*
X589137Y1100173D03*
X603787Y1122953D03*
Y1113504D03*
Y1104055D03*
X570287Y1140173D03*
Y1152673D03*
X567500Y1189500D03*
X586087Y1182373D03*
X592287Y1205673D03*
X590000Y1247000D03*
X567374Y1369303D03*
X572374D03*
X577374D03*
X582374D03*
X587374D03*
X592374D03*
X597374D03*
X602374D03*
X562374D03*
X609146Y5500D03*
X619146D03*
X614146D03*
X629146D03*
X639146D03*
X649146D03*
X654146D03*
X644146D03*
X634146D03*
X624146D03*
X613500Y66000D03*
X634500Y77000D03*
X629024Y107633D03*
X614967Y134777D03*
X606718Y168580D03*
X639537Y237161D03*
X608287Y245492D03*
Y235492D03*
X649500Y285000D03*
X608287Y275492D03*
X607961Y263934D03*
X650000Y322500D03*
X615287Y314114D03*
X649000Y429500D03*
X643000Y549500D03*
X620153Y511994D03*
X634388Y511957D03*
X615100Y513287D03*
X638646Y515994D03*
X624411Y516031D03*
X615287Y594626D03*
X608287Y648248D03*
Y633248D03*
Y618248D03*
Y688248D03*
X639537Y689917D03*
X650659Y744673D03*
X608287Y728248D03*
Y718248D03*
Y698248D03*
X637326Y732212D03*
X650668Y720583D03*
X650711Y710495D03*
X631500Y774000D03*
X615287Y766870D03*
X642000Y889500D03*
X632000Y936000D03*
X654000Y911000D03*
X646500Y898500D03*
X634000Y988000D03*
X638500Y1046500D03*
X608287Y1071004D03*
X615287Y1047382D03*
X608287Y1101004D03*
Y1086004D03*
X643000Y1146173D03*
X608287Y1171004D03*
Y1151004D03*
Y1141004D03*
X651216Y1164051D03*
X615238Y1218951D03*
X608287Y1181004D03*
X650644Y1197038D03*
X650626Y1182447D03*
X617374Y1369303D03*
X622374D03*
X627374D03*
X632374D03*
X637374D03*
X642374D03*
X647374D03*
X652374D03*
X607374D03*
X612374D03*
X679146Y5500D03*
X689146D03*
X694146D03*
X684146D03*
X659146D03*
X669146D03*
X664146D03*
X674146D03*
X699146D03*
X700000Y60000D03*
X675000Y75500D03*
X697457Y107247D03*
X697483Y111500D03*
X661965Y106177D03*
X658500Y184500D03*
X695137Y189130D03*
X685545Y212806D03*
X689426Y236628D03*
X694500Y247161D03*
X670500Y254661D03*
X673500Y344000D03*
X698500Y415500D03*
X695500Y462500D03*
X670000Y531500D03*
X696000Y641717D03*
X694500Y687417D03*
X685550Y665417D03*
X670500Y707417D03*
X694500Y699917D03*
X691500Y778000D03*
X692500Y790500D03*
X678500Y776500D03*
X673500Y752000D03*
X696000Y1092973D03*
X685250Y1113673D03*
X667700Y1160173D03*
X694500Y1140173D03*
X692671Y1152747D03*
X668000Y1195000D03*
X680500Y1208500D03*
X698500Y1306500D03*
X667374Y1369303D03*
X672374D03*
X677374D03*
X682374D03*
X687374D03*
X692374D03*
X697374D03*
X702374D03*
X657374D03*
X662374D03*
X749146Y5500D03*
X709146D03*
X719146D03*
X729146D03*
X739146D03*
X744146D03*
X734146D03*
X724146D03*
X714146D03*
X704146D03*
X740000Y40000D03*
X720000D03*
Y60000D03*
X740000D03*
X724645Y138941D03*
X732500Y180492D03*
Y165492D03*
X728000Y207992D03*
Y198543D03*
X732100Y198373D03*
X707700Y194861D03*
X713350Y194661D03*
X728000Y217441D03*
X732500Y245492D03*
X731048Y238563D03*
X738361Y306612D03*
X732500Y275492D03*
Y265492D03*
X710300Y276861D03*
X716500Y300161D03*
X724000Y338500D03*
X748000Y368500D03*
X726000Y369000D03*
X732000Y374500D03*
Y383000D03*
X748500Y409000D03*
X721500Y462500D03*
X727500Y476000D03*
X724000Y583500D03*
X702500Y563000D03*
X739500Y594626D03*
X732500Y648248D03*
Y633248D03*
Y618248D03*
X713350Y647417D03*
X704500Y672000D03*
X728000Y670197D03*
X732500Y688248D03*
X728000Y660748D03*
Y651299D03*
X707700Y649117D03*
X732500Y728248D03*
Y718248D03*
Y698248D03*
X710300Y729617D03*
X748000Y783000D03*
X739500Y766870D03*
X716500Y752917D03*
X745000Y833000D03*
X704500Y795000D03*
X747656Y876717D03*
X709500Y894500D03*
X712000Y1046000D03*
X732500Y1071004D03*
X739500Y1047382D03*
X728000Y1122953D03*
Y1113504D03*
Y1104055D03*
X732500Y1101004D03*
Y1086004D03*
X713350Y1100173D03*
X707700Y1100373D03*
X716000Y1136000D03*
X732500Y1171004D03*
Y1151004D03*
Y1141004D03*
X739500Y1219626D03*
X732500Y1181004D03*
X710300Y1182373D03*
X716500Y1205673D03*
X747374Y1369303D03*
X742374D03*
X717374D03*
X722374D03*
X727374D03*
X732374D03*
X737374D03*
X707374D03*
X712374D03*
X795969Y-1374D03*
X759146Y5500D03*
X769146D03*
X774146D03*
X764146D03*
X754146D03*
X779146D03*
X789045Y11615D03*
X780000Y40000D03*
X760000D03*
Y60000D03*
X780000D03*
X752950Y213450D03*
X771500Y311000D03*
X764000Y439500D03*
X767500Y463500D03*
X772000Y479500D03*
X787000Y514000D03*
X798140Y630220D03*
X798210Y626440D03*
X798367Y622400D03*
X751750Y685300D03*
X793000Y828000D03*
Y851000D03*
X778000Y988500D03*
X762500D03*
X763000Y1075000D03*
X781000Y1373000D03*
X755500Y1374500D03*
X752500Y1370500D03*
X757287Y1380873D03*
Y1385873D03*
Y1390873D03*
Y1395873D03*
Y1400873D03*
Y1405873D03*
Y1410873D03*
Y1415873D03*
Y1420873D03*
X784000Y1443000D03*
X757287Y1425873D03*
Y1430873D03*
Y1435873D03*
Y1440873D03*
Y1445873D03*
X766156Y1462004D03*
X771156D03*
X790500Y1466500D03*
X786000Y1463500D03*
X756287Y1459264D03*
Y1454264D03*
X779547Y1463004D03*
X792902Y1477964D03*
Y1487964D03*
Y1497964D03*
Y1507964D03*
Y1517964D03*
Y1512964D03*
Y1472964D03*
Y1482964D03*
Y1492964D03*
Y1502964D03*
Y1562964D03*
Y1527964D03*
Y1537964D03*
Y1547964D03*
Y1557964D03*
Y1567964D03*
Y1522964D03*
Y1532964D03*
Y1542964D03*
Y1552964D03*
Y1612964D03*
Y1602964D03*
Y1592964D03*
Y1582964D03*
Y1572964D03*
Y1577964D03*
Y1587964D03*
Y1597964D03*
Y1607964D03*
X797902Y1652964D03*
X792902D03*
Y1642964D03*
Y1632964D03*
Y1622964D03*
Y1627964D03*
Y1637964D03*
Y1647964D03*
Y1617964D03*
X845961Y61762D03*
Y56762D03*
Y52762D03*
X846000Y116500D03*
X811500Y372000D03*
X800000Y400000D03*
X811500Y469500D03*
X846400Y469300D03*
X839000Y541000D03*
X839500Y560000D03*
X800867Y619400D03*
X803367Y622400D03*
X827500Y922500D03*
X839414Y1520763D03*
X833859Y1594095D03*
Y1608268D03*
X840945Y1598032D03*
X826772D03*
X840945Y1612205D03*
X826772D03*
X833859Y1622441D03*
Y1636614D03*
Y1650788D03*
X840945Y1626378D03*
X826772D03*
X840945Y1640551D03*
X826772D03*
X872642Y-140575D03*
Y-135575D03*
Y-130575D03*
Y-125575D03*
X890264Y-147256D03*
X880264D03*
X875264D03*
X885264D03*
X895264D03*
X882000Y-105500D03*
X872642Y-80575D03*
Y-120575D03*
Y-115575D03*
Y-110575D03*
Y-105575D03*
Y-100575D03*
Y-95575D03*
Y-90575D03*
Y-85575D03*
Y-30575D03*
Y-35575D03*
Y-40575D03*
Y-45575D03*
Y-50575D03*
Y-55575D03*
Y-60575D03*
Y-65575D03*
Y-70575D03*
Y-75575D03*
Y-20575D03*
Y-25575D03*
X885046Y20384D03*
X861101Y66680D03*
X862099Y61626D03*
Y56626D03*
X861961Y52762D03*
X852769Y66957D03*
X848769D03*
X856769D03*
X853961Y52762D03*
X849961D03*
X857961D03*
X874244Y37026D03*
Y44935D03*
X852769Y74957D03*
X856769D03*
X861142Y71026D03*
X852810Y71303D03*
X856810D03*
X853900Y89701D03*
X888500Y260500D03*
X850500Y266000D03*
X866000Y315000D03*
X856500Y373000D03*
X855500Y499500D03*
X871487Y463589D03*
X860092Y542405D03*
X867500Y643000D03*
X877000Y664500D03*
X868500Y665000D03*
X885600Y824400D03*
X867663Y818831D03*
X885301Y1358557D03*
X884746Y1350438D03*
X873495Y1370213D03*
X885300Y1371050D03*
X877300Y1432400D03*
X886500Y1432500D03*
X893158Y1516542D03*
X893050Y1489500D03*
X868791Y1478782D03*
X892682Y1520718D03*
X855092Y1535821D03*
X866621Y1544206D03*
X876378Y1594095D03*
X862205D03*
X848032D03*
X876378Y1608268D03*
X862205D03*
X848032D03*
X890552Y1598032D03*
X869292D03*
X855118D03*
X869292Y1612205D03*
X855118D03*
X876378Y1622441D03*
X862205D03*
X848032D03*
X876378Y1636614D03*
X862205D03*
X848032D03*
X876378Y1650788D03*
X862205D03*
X848032D03*
X869292Y1626378D03*
X855118D03*
X869292Y1640551D03*
X855118D03*
X910500Y-137500D03*
X940264Y-147256D03*
X930264D03*
X925264D03*
X935264D03*
X920264D03*
X910264D03*
X900264D03*
X905264D03*
X915264D03*
X902000Y-58000D03*
X909000Y89000D03*
X898000Y133000D03*
X911000Y305500D03*
X898000Y268000D03*
X915000Y879000D03*
X926185Y928342D03*
X924974Y933041D03*
X914876Y901029D03*
X937621Y915324D03*
X924563Y962945D03*
X919759Y970868D03*
X938009Y987330D03*
X941868Y952101D03*
X916446Y1035438D03*
X941640Y995820D03*
X929257Y1035883D03*
X932564Y1346100D03*
X904941Y1456941D03*
X918505Y1530405D03*
X918800Y1534500D03*
X897638Y1594095D03*
X960264Y-147256D03*
X950264D03*
X955264D03*
X965264D03*
X945264D03*
X990264D03*
X980264D03*
X970264D03*
X975264D03*
X985264D03*
X975500Y11500D03*
X974000Y402000D03*
Y523000D03*
X985500Y613500D03*
X978000Y677000D03*
X981580Y932678D03*
X976580Y986180D03*
X959400Y960300D03*
X987970Y1004157D03*
X955700Y1030700D03*
X977400Y1157900D03*
X977500Y1182300D03*
X962500Y1298500D03*
X988624Y1502923D03*
X951815Y1491459D03*
X1010264Y-147256D03*
X1000264D03*
X1005264D03*
X1015264D03*
X995264D03*
X1040264D03*
X1030264D03*
X1020264D03*
X1025264D03*
X1035264D03*
X1015582Y-69800D03*
X1014800Y-62100D03*
X999300Y-64400D03*
X1009100Y-48600D03*
X1035000Y-66800D03*
X1022618Y-36900D03*
X1023300Y-44200D03*
X1032053Y-34953D03*
X1038712Y-34812D03*
X1017600Y63600D03*
Y58900D03*
Y54200D03*
X993000Y108000D03*
X1036003Y93543D03*
X1038503Y97543D03*
X1033503D03*
Y102543D03*
Y107543D03*
Y112543D03*
X993000Y157000D03*
Y329000D03*
X998000Y378000D03*
X995000Y455000D03*
Y488000D03*
X1018322Y545207D03*
X1018300Y550000D03*
X993000Y635000D03*
X1025000Y817000D03*
X1028472Y834829D03*
X1027063Y850703D03*
X1014891Y943357D03*
X1013713Y974651D03*
X997694Y974940D03*
X1012494Y1033840D03*
X1018000Y1076500D03*
X1031400Y1124700D03*
X1019000Y1178000D03*
X1013400Y1137500D03*
X1021991Y1141526D03*
X1004294Y1137600D03*
X997500Y1192500D03*
X1006800Y1191200D03*
X1032500Y1248000D03*
X993500Y1317000D03*
X1031000Y1350500D03*
X1031474Y1354526D03*
X1060264Y-147256D03*
X1050264D03*
X1055264D03*
X1065264D03*
X1045264D03*
X1080264D03*
X1070264D03*
X1075264D03*
X1085264D03*
X1065621Y-85082D03*
X1084200Y-82300D03*
X1074400Y-81000D03*
X1070500Y-67900D03*
X1074400Y-39100D03*
X1079600Y-50700D03*
X1087700Y-37886D03*
X1045800Y-75936D03*
X1058333Y-72770D03*
X1061325Y-40378D03*
X1054625Y-40278D03*
X1078500Y99000D03*
X1043703Y112543D03*
Y107543D03*
Y102543D03*
X1041003Y93543D03*
X1043703Y97543D03*
X1078500Y135500D03*
X1043500Y310500D03*
X1048500Y346000D03*
X1058500Y368500D03*
X1045000Y364000D03*
X1042833Y434409D03*
X1047000Y492000D03*
X1079000Y477000D03*
X1058000D03*
X1045106Y561249D03*
X1058000Y616000D03*
X1073000Y676000D03*
X1047000Y751000D03*
X1045163Y840400D03*
X1082000Y815500D03*
X1054000Y866000D03*
X1075500Y848000D03*
X1072000Y1035000D03*
X1052000Y1054000D03*
X1054080Y1077680D03*
X1087700Y1125800D03*
X1078098Y1652768D03*
X1073098D03*
X1083098D03*
X1088098D03*
X1110264Y-147256D03*
X1100264D03*
X1090264D03*
X1105264D03*
X1095264D03*
X1130264D03*
X1120264D03*
X1115264D03*
X1125264D03*
X1135264D03*
X1134500Y-103500D03*
X1115000Y-77500D03*
X1097600Y-82462D03*
X1107700Y-76800D03*
X1114400Y-55662D03*
X1093900Y-64500D03*
X1113300Y-44100D03*
X1137446Y1024025D03*
Y1009852D03*
Y995679D03*
Y1038198D03*
X1124100Y1125100D03*
X1137446Y1167343D03*
Y1224036D03*
Y1209863D03*
Y1195690D03*
Y1181516D03*
Y1266556D03*
Y1252383D03*
Y1238209D03*
Y1309076D03*
Y1323249D03*
Y1294902D03*
Y1280729D03*
Y1365769D03*
Y1351595D03*
Y1337422D03*
Y1394115D03*
Y1408288D03*
Y1379942D03*
X1093098Y1652768D03*
X1133098D03*
X1123098D03*
X1113098D03*
X1103098D03*
X1108098D03*
X1118098D03*
X1128098D03*
X1098098D03*
X1170264Y-147256D03*
X1155264D03*
X1175602Y-137594D03*
Y-127594D03*
X1160264Y-147256D03*
X1150264D03*
X1140264D03*
X1145264D03*
X1175602Y-132594D03*
Y-142594D03*
X1165264Y-147256D03*
X1175602Y-117594D03*
Y-107594D03*
Y-97594D03*
Y-87594D03*
Y-77594D03*
Y-82594D03*
Y-92594D03*
Y-102594D03*
Y-112594D03*
Y-122594D03*
X1139500Y-58500D03*
X1150000Y-63000D03*
X1175602Y-67594D03*
Y-57594D03*
Y-47594D03*
Y-37594D03*
Y-32594D03*
Y-42594D03*
Y-52594D03*
Y-62594D03*
Y-72594D03*
Y-17594D03*
Y-27594D03*
X1180500Y4000D03*
X1176500Y-500D03*
X1175602Y-22594D03*
Y-12594D03*
Y-7594D03*
X1184088Y101360D03*
X1184141Y96794D03*
X1177500Y153500D03*
X1173500Y397000D03*
X1156500Y467000D03*
X1166500Y635000D03*
X1156500Y619000D03*
X1176835Y618934D03*
X1156500Y650000D03*
X1181000Y814000D03*
X1156500Y813000D03*
X1179000Y829500D03*
X1166500D03*
X1158500Y868500D03*
X1144580Y1078680D03*
X1172564Y1118373D03*
X1162000Y1371500D03*
X1169783Y1369303D03*
X1179783D03*
X1174783D03*
X1184783D03*
X1158673Y1417067D03*
Y1407067D03*
Y1397067D03*
Y1387067D03*
Y1377067D03*
Y1412067D03*
Y1402067D03*
Y1392067D03*
Y1382067D03*
Y1422067D03*
Y1442067D03*
Y1452067D03*
X1158500Y1468500D03*
X1158673Y1457067D03*
Y1447067D03*
Y1437067D03*
Y1427067D03*
Y1462067D03*
Y1432067D03*
X1153000Y1496000D03*
X1161000Y1474500D03*
X1166673Y1477941D03*
X1171673D03*
X1181673D03*
X1176673D03*
X1163000Y1612000D03*
X1141000Y1632000D03*
X1143098Y1652768D03*
X1183098D03*
X1173098D03*
X1163098D03*
X1153098D03*
X1158098D03*
X1168098D03*
X1178098D03*
X1138098D03*
X1148098D03*
X1228500Y12500D03*
X1191382Y5500D03*
X1196382D03*
X1186382D03*
X1201382D03*
X1211382D03*
X1221382D03*
X1231382D03*
X1226382D03*
X1216382D03*
X1206382D03*
X1204768Y64368D03*
X1199768D03*
X1209768D03*
X1204068Y50368D03*
Y45368D03*
X1203768Y60568D03*
Y55568D03*
X1224000Y104000D03*
X1199768Y69368D03*
X1204768D03*
X1209768D03*
X1204768Y85368D03*
X1199768D03*
X1209768D03*
Y89368D03*
X1199768D03*
X1204768D03*
X1186500Y220500D03*
X1224800Y225200D03*
X1219917Y239646D03*
X1232500Y541000D03*
X1197868Y730300D03*
X1194268D03*
Y723100D03*
Y726700D03*
X1197868Y723100D03*
Y726700D03*
X1192068Y712300D03*
X1195668D03*
X1192068Y715900D03*
X1195668D03*
Y719500D03*
X1192068D03*
X1188000Y753000D03*
X1192000Y869000D03*
X1232700Y950400D03*
X1229691Y1148580D03*
X1214500Y1320500D03*
X1220500Y1311000D03*
X1199783Y1369303D03*
X1209783D03*
X1219783D03*
X1229783D03*
X1189783D03*
X1224783D03*
X1214783D03*
X1204783D03*
X1194783D03*
X1194000Y1499000D03*
X1191673Y1477941D03*
X1201673D03*
X1214972Y1482642D03*
Y1517642D03*
Y1487642D03*
Y1497642D03*
Y1507642D03*
Y1512642D03*
Y1502642D03*
Y1492642D03*
X1206673Y1477941D03*
X1196673D03*
X1186673D03*
X1211673D03*
X1214972Y1567642D03*
Y1527642D03*
Y1537642D03*
Y1547642D03*
Y1557642D03*
Y1562642D03*
Y1552642D03*
Y1542642D03*
Y1532642D03*
Y1522642D03*
Y1577642D03*
Y1587642D03*
Y1597642D03*
Y1607642D03*
Y1612642D03*
Y1602642D03*
Y1592642D03*
Y1582642D03*
Y1572642D03*
Y1617642D03*
Y1627642D03*
Y1637642D03*
X1213098Y1652768D03*
X1193098D03*
X1203098D03*
X1208098D03*
X1214972Y1642642D03*
Y1632642D03*
X1188098Y1652768D03*
X1198098D03*
X1214972Y1622642D03*
Y1647642D03*
X1240500Y20000D03*
X1251382Y5500D03*
X1261382D03*
X1271382D03*
X1281382D03*
X1276382D03*
X1266382D03*
X1256382D03*
X1241382D03*
X1246382D03*
X1236382D03*
X1254000Y105000D03*
X1281500Y103500D03*
X1278900Y182823D03*
X1266400D03*
X1278421Y205974D03*
X1281603Y203340D03*
X1282106Y180492D03*
X1280800Y167200D03*
X1282287Y243489D03*
X1277606Y217441D03*
X1282106Y235492D03*
X1248193Y242618D03*
X1255600Y237300D03*
X1273200Y263700D03*
X1276200Y277400D03*
X1280000Y430000D03*
X1235796Y517450D03*
X1250011Y516707D03*
X1282106Y648248D03*
Y633248D03*
Y618248D03*
X1253800Y689600D03*
X1277606Y670197D03*
X1282106Y688248D03*
X1277606Y660748D03*
Y651299D03*
X1282106Y728248D03*
Y718248D03*
Y698248D03*
X1250475Y969248D03*
X1279081Y1071085D03*
X1277606Y1122953D03*
Y1113504D03*
Y1104055D03*
X1282106Y1101004D03*
Y1086004D03*
X1251250Y1141700D03*
X1282106Y1171004D03*
Y1151004D03*
Y1141004D03*
X1246557Y1148155D03*
X1249600Y1155800D03*
X1282106Y1181004D03*
X1257000Y1300000D03*
X1263500Y1318500D03*
X1249783Y1369303D03*
X1259783D03*
X1269783D03*
X1279783D03*
X1239783D03*
X1274783D03*
X1264783D03*
X1254783D03*
X1234783D03*
X1244783D03*
X1319000Y12000D03*
X1301382Y5500D03*
X1311382D03*
X1296382D03*
X1316382D03*
X1306382D03*
X1291382D03*
X1286382D03*
X1326382D03*
X1321382D03*
X1309000Y45500D03*
X1318500Y34500D03*
X1319100Y78800D03*
X1323521Y79179D03*
X1312999Y107280D03*
X1317661Y107896D03*
X1299569Y84272D03*
X1304563Y84309D03*
X1289000Y145400D03*
X1302074Y183779D03*
X1311200Y172661D03*
X1304293Y165909D03*
X1315838Y188804D03*
X1297507Y195492D03*
X1298700Y272800D03*
X1298500Y302900D03*
X1305000Y299400D03*
X1313000Y302900D03*
X1313915Y263541D03*
X1289000Y309500D03*
X1311000Y321000D03*
X1303500Y434000D03*
X1287000Y456000D03*
X1310000Y597000D03*
X1289106Y594626D03*
X1303800Y636417D03*
X1311200Y625417D03*
X1307500Y615417D03*
X1315400Y648017D03*
X1302500Y718917D03*
X1314000Y717417D03*
X1298500Y752417D03*
X1305000D03*
X1313000D03*
X1289106Y766870D03*
X1305000Y1041500D03*
X1289114Y1048624D03*
X1311200Y1078173D03*
X1305100Y1068173D03*
X1303800Y1089173D03*
X1315300Y1100773D03*
X1302500Y1171673D03*
X1313950Y1165990D03*
X1300065Y1206008D03*
X1305000Y1205173D03*
X1313000D03*
X1289106Y1219626D03*
X1299783Y1369303D03*
X1309783D03*
X1319783D03*
X1329783D03*
X1289783D03*
X1324783D03*
X1314783D03*
X1304783D03*
X1294783D03*
X1284783D03*
X1363579Y19821D03*
Y14821D03*
Y9821D03*
X1351382Y5500D03*
X1356382D03*
X1346382D03*
X1336382D03*
X1341382D03*
X1331382D03*
X1357500Y43500D03*
X1347500Y21000D03*
X1363579Y44821D03*
Y39821D03*
Y34821D03*
Y29821D03*
Y24821D03*
X1374000Y64500D03*
X1363579Y51618D03*
X1332500Y56500D03*
X1351201Y90099D03*
X1332934Y137712D03*
X1377463Y237100D03*
X1372000Y335000D03*
X1338000Y546500D03*
X1346363Y516578D03*
X1332148Y517321D03*
X1337500Y576500D03*
X1372272Y573560D03*
X1375463Y689917D03*
X1339500Y794000D03*
X1344000Y987500D03*
X1362000Y987000D03*
X1331070Y966090D03*
X1348796Y969488D03*
X1368935Y1123365D03*
X1365461Y1136100D03*
X1375463Y1142673D03*
X1364713Y1143791D03*
X1349783Y1369303D03*
X1359783D03*
X1369783D03*
X1339783D03*
X1374783D03*
X1364783D03*
X1354783D03*
X1344783D03*
X1334783D03*
X1413268Y146062D03*
X1401819Y207992D03*
X1394705Y195413D03*
X1406319Y180492D03*
X1405100Y166000D03*
X1403963Y245492D03*
X1385051Y218684D03*
X1406000Y236700D03*
X1426713Y266161D03*
X1426400Y307400D03*
X1406319Y275492D03*
Y265492D03*
X1400000Y406000D03*
X1427000Y380000D03*
X1425000Y480000D03*
X1405000D03*
Y460000D03*
X1385000Y480000D03*
X1396500Y511000D03*
X1383500Y509500D03*
X1413319Y594626D03*
X1406319Y648248D03*
Y633248D03*
Y618248D03*
X1421500Y664000D03*
X1401819Y670197D03*
X1406319Y688248D03*
X1401819Y660748D03*
Y651299D03*
X1426713Y718917D03*
X1406319Y728248D03*
Y718248D03*
Y698248D03*
X1422713Y752417D03*
X1398245Y766870D03*
X1395000Y791500D03*
X1390000Y955500D03*
X1390500Y1048000D03*
X1406319Y1071004D03*
X1413319Y1047382D03*
X1406319Y1086004D03*
Y1101004D03*
X1401819Y1104055D03*
X1385494Y1113504D03*
X1401819Y1122953D03*
X1406319Y1141004D03*
Y1151004D03*
Y1171004D03*
X1426713Y1171673D03*
X1406319Y1181004D03*
X1413319Y1219626D03*
X1422713Y1205173D03*
X1413000Y1241500D03*
X1387000Y1243500D03*
X1386500Y1258000D03*
X1418000Y1291500D03*
X1400000Y1320000D03*
X1420000D03*
X1399783Y1369303D03*
X1409783D03*
X1419783D03*
X1379783D03*
X1389783D03*
X1404783D03*
X1414783D03*
X1424783D03*
X1394783D03*
X1384783D03*
X1431713Y162661D03*
X1428013Y185956D03*
X1445994Y174086D03*
X1440300Y188000D03*
X1438186Y261287D03*
X1463000Y307000D03*
X1439300Y301500D03*
X1429800Y302500D03*
X1447170Y337890D03*
X1466500Y338100D03*
X1441770Y365790D03*
X1461100Y366000D03*
X1441970Y403990D03*
X1461300Y404200D03*
X1439500Y421500D03*
X1440000Y460000D03*
X1449576Y495482D03*
X1468605Y493549D03*
X1452279Y563600D03*
X1464700Y585600D03*
X1470000Y580000D03*
X1460274Y592498D03*
X1428013Y636417D03*
X1435413Y625417D03*
X1431713Y615417D03*
X1439713Y647917D03*
X1449000Y698000D03*
X1438087Y713756D03*
X1429213Y752417D03*
X1437213D03*
X1432000Y831000D03*
X1459500Y814000D03*
X1450500Y802500D03*
X1459500Y796500D03*
X1473000Y798000D03*
X1433500Y864500D03*
X1457500Y987500D03*
X1440000Y986500D03*
X1473008Y969646D03*
X1458967Y969535D03*
X1433500Y1044000D03*
X1456000D03*
X1435413Y1078173D03*
X1431713Y1068173D03*
X1428013Y1089173D03*
X1439713Y1100773D03*
X1438213Y1170173D03*
X1429213Y1205173D03*
X1437213D03*
X1458000Y1265500D03*
X1460000Y1300000D03*
Y1320000D03*
X1440000D03*
X1449783Y1369303D03*
X1459783D03*
X1469783D03*
X1429783D03*
X1439783D03*
X1444783D03*
X1454783D03*
X1464783D03*
X1474783D03*
X1434783D03*
X1515450Y181700D03*
X1502950D03*
X1498900Y235800D03*
X1505000Y378500D03*
X1520000Y421500D03*
X1479212Y535612D03*
X1494100Y526400D03*
X1507900Y539100D03*
X1481938Y512568D03*
X1509911Y553511D03*
X1478700Y579100D03*
X1502400Y554100D03*
X1494462Y692179D03*
X1515000Y789000D03*
X1520000Y776000D03*
X1499500Y774000D03*
Y831000D03*
X1510500Y878000D03*
X1510000Y860500D03*
X1512500Y949000D03*
X1508500Y1028500D03*
Y1050500D03*
X1488500Y1096000D03*
X1489096Y1131456D03*
X1489108Y1121674D03*
X1499675Y1142673D03*
X1489333Y1147664D03*
X1480000Y1320000D03*
X1499783Y1369303D03*
X1509783D03*
X1519783D03*
X1479783D03*
X1489783D03*
X1494783D03*
X1484783D03*
X1504783D03*
X1514783D03*
X1565555Y16517D03*
X1568030Y5500D03*
X1565555Y21517D03*
Y26517D03*
Y31517D03*
Y36517D03*
Y41517D03*
X1557000Y64500D03*
X1561500Y62000D03*
X1564000Y57500D03*
X1564555Y52124D03*
X1525336Y149369D03*
X1555925Y162661D03*
X1545383Y164116D03*
X1560000Y140000D03*
X1552225Y183661D03*
X1559625Y172661D03*
X1563925Y195261D03*
X1526031Y207992D03*
Y198543D03*
X1530531Y195492D03*
Y180492D03*
Y245492D03*
X1526031Y217441D03*
X1530142Y238021D03*
X1550925Y266161D03*
X1546925Y299661D03*
X1553425D03*
X1561425D03*
X1562425Y264661D03*
X1530531Y275492D03*
Y265492D03*
X1537531Y314114D03*
X1545000Y455000D03*
X1560000D03*
X1525000D03*
X1545000Y475000D03*
X1560000D03*
Y500000D03*
Y525000D03*
X1552000Y584500D03*
X1566000Y595000D03*
X1537531Y594626D03*
X1552225Y636417D03*
X1559625Y625417D03*
X1555925Y615417D03*
X1530531Y648248D03*
Y633248D03*
Y618248D03*
X1558925Y650017D03*
X1526031Y670197D03*
X1530531Y688248D03*
X1526031Y660748D03*
Y651299D03*
X1550925Y718917D03*
X1562425Y717417D03*
X1530531Y728248D03*
Y718248D03*
Y698248D03*
X1555000Y770000D03*
X1546925Y752417D03*
X1553425D03*
X1561425D03*
X1537531Y766870D03*
X1525000Y878000D03*
X1564500Y931000D03*
X1548500Y933000D03*
X1564000Y949000D03*
X1552500Y1028000D03*
X1557500Y1043500D03*
X1537531Y1047382D03*
X1559625Y1078173D03*
X1555925Y1068173D03*
X1530531Y1071004D03*
X1552225Y1089173D03*
X1526031Y1122953D03*
Y1113504D03*
Y1104055D03*
X1530531Y1101004D03*
Y1086004D03*
X1550925Y1171673D03*
X1552575Y1139700D03*
X1562425Y1170173D03*
X1530531Y1171004D03*
Y1151004D03*
X1528723Y1138918D03*
X1546898Y1204827D03*
X1553425Y1208897D03*
X1561425Y1205173D03*
X1537879Y1219626D03*
X1530531Y1181004D03*
X1549783Y1369303D03*
X1559783D03*
X1569783D03*
X1529783D03*
X1539783D03*
X1524783D03*
X1534783D03*
X1544783D03*
X1554783D03*
X1564783D03*
X1600000Y20000D03*
X1620000D03*
X1580000D03*
X1603030Y5500D03*
X1613030D03*
X1573030D03*
X1583030D03*
X1593030D03*
X1618030D03*
X1608030D03*
X1598030D03*
X1588030D03*
X1578030D03*
X1600000Y60000D03*
X1620000Y40000D03*
X1600000D03*
X1580000D03*
Y60000D03*
X1620000Y100000D03*
X1600000Y80000D03*
X1620000D03*
X1580000D03*
X1620000Y140000D03*
Y120000D03*
X1585757Y134147D03*
X1607000Y199000D03*
X1595500Y258500D03*
X1621100Y240561D03*
X1608000Y256000D03*
X1600000Y340000D03*
X1620000D03*
Y320000D03*
X1600000D03*
X1579500Y331000D03*
X1597245Y516662D03*
X1583030Y517405D03*
X1573000Y565500D03*
X1580000Y780000D03*
X1576500Y928500D03*
X1597221Y969572D03*
X1583180Y969461D03*
X1596000Y990000D03*
X1611500Y1078000D03*
X1593000Y1043500D03*
X1593500Y1185500D03*
X1581500Y1240000D03*
X1600000Y1320000D03*
X1614783Y1369303D03*
X1604783D03*
X1599783D03*
X1609783D03*
X1619783D03*
X1579783D03*
X1589783D03*
X1574783D03*
X1584783D03*
X1594783D03*
X1640000Y20000D03*
X1660000D03*
X1653030Y5500D03*
X1663030D03*
X1623030D03*
X1633030D03*
X1643030D03*
X1668030D03*
X1658030D03*
X1648030D03*
X1638030D03*
X1628030D03*
X1640000Y60000D03*
X1660000D03*
Y40000D03*
X1640000D03*
Y100000D03*
X1660000D03*
X1640000Y80000D03*
X1660000D03*
Y120000D03*
X1640000D03*
X1661744Y141870D03*
X1650244Y207992D03*
Y198543D03*
X1654744Y195492D03*
Y180492D03*
Y165492D03*
Y245492D03*
X1650244Y217441D03*
X1654744Y235492D03*
X1652387Y277343D03*
X1653789Y267766D03*
X1639000Y320000D03*
X1640000Y340000D03*
X1660000D03*
X1661744Y314114D03*
X1660000Y400000D03*
X1640000Y360000D03*
X1660000Y440000D03*
Y480000D03*
X1640000D03*
Y460000D03*
X1660000D03*
X1640000Y500000D03*
X1660000D03*
Y520000D03*
X1640000D03*
X1660000Y540000D03*
X1640000D03*
Y560000D03*
X1660000D03*
X1661744Y594626D03*
X1654744Y648248D03*
Y633248D03*
Y618248D03*
X1623888Y689917D03*
X1652962Y670204D03*
X1654744Y688248D03*
X1650244Y660748D03*
Y651299D03*
X1637000Y729000D03*
X1638000Y740000D03*
X1654744Y728248D03*
Y718248D03*
Y698248D03*
X1630000Y780000D03*
Y760000D03*
X1661744Y766870D03*
X1625000Y800000D03*
X1651500Y913500D03*
X1650000Y950000D03*
Y980000D03*
X1653500Y1016500D03*
X1650000Y1000000D03*
X1632000Y1049500D03*
X1654744Y1071004D03*
X1661744Y1047382D03*
X1650244Y1122953D03*
Y1113504D03*
Y1104055D03*
X1654744Y1101004D03*
Y1086004D03*
X1627563Y1132075D03*
X1627802Y1118949D03*
X1627769Y1110037D03*
X1635688Y1141158D03*
X1650841Y1168660D03*
X1654744Y1151004D03*
Y1141004D03*
X1627197Y1143044D03*
X1661744Y1219626D03*
X1668378Y1181004D03*
X1640000Y1260000D03*
X1660000D03*
X1640000Y1320000D03*
Y1300000D03*
X1660000Y1320000D03*
Y1300000D03*
Y1280000D03*
X1640000D03*
X1664783Y1369303D03*
X1654783D03*
X1644783D03*
X1634783D03*
X1624783D03*
X1649783D03*
X1659783D03*
X1629783D03*
X1639783D03*
X1700000Y20000D03*
X1680000D03*
X1703030Y5500D03*
X1713030D03*
X1673030D03*
X1683030D03*
X1693030D03*
X1718030D03*
X1708030D03*
X1698030D03*
X1688030D03*
X1678030D03*
X1700000Y60000D03*
Y40000D03*
X1680000Y60000D03*
Y40000D03*
Y100000D03*
Y80000D03*
X1700000Y100000D03*
Y80000D03*
Y140000D03*
Y120000D03*
X1680000D03*
X1679500Y144000D03*
X1680138Y162661D03*
X1676438Y183661D03*
X1683838Y172661D03*
X1688138Y195261D03*
X1675475Y267424D03*
X1671138Y299661D03*
X1677638D03*
X1685638D03*
X1686638Y264661D03*
X1678500Y320000D03*
X1700000Y400000D03*
X1680000Y380000D03*
X1700000Y360000D03*
X1680000Y440000D03*
Y420000D03*
X1700000Y440000D03*
Y420000D03*
Y460000D03*
X1680000Y480000D03*
Y460000D03*
Y500000D03*
Y520000D03*
X1700000Y540000D03*
X1680000D03*
X1707495Y517152D03*
X1700000Y560000D03*
X1680000D03*
X1676438Y636417D03*
X1683838Y625417D03*
X1680138Y615417D03*
X1688138Y648017D03*
X1675138Y718917D03*
X1686638Y717417D03*
X1710000Y770000D03*
Y785000D03*
X1685000Y770000D03*
X1671138Y752417D03*
X1677638D03*
X1685638D03*
X1709000Y915000D03*
X1687000Y905500D03*
X1716500Y943500D03*
X1706000Y1022000D03*
X1683838Y1078173D03*
X1680138Y1068173D03*
X1688138Y1100773D03*
X1676438Y1089173D03*
X1686638Y1170173D03*
X1675138Y1171673D03*
X1685638Y1205173D03*
X1677638D03*
X1671138D03*
X1680000Y1240000D03*
X1700000Y1260000D03*
X1680000D03*
X1700000Y1320000D03*
Y1300000D03*
Y1280000D03*
X1680000Y1320000D03*
Y1300000D03*
Y1280000D03*
X1714783Y1369303D03*
X1704783D03*
X1694783D03*
X1684783D03*
X1674783D03*
X1699783D03*
X1709783D03*
X1669783D03*
X1679783D03*
X1689783D03*
X1760000Y20000D03*
X1740000D03*
X1720000D03*
X1753030Y5500D03*
X1763030D03*
X1723030D03*
X1733030D03*
X1743030D03*
X1758030D03*
X1748030D03*
X1738030D03*
X1728030D03*
X1760000Y60000D03*
Y40000D03*
X1740000D03*
Y60000D03*
X1720000Y40000D03*
Y60000D03*
X1740000Y100000D03*
X1760000D03*
X1740000Y80000D03*
X1760000D03*
X1720000Y100000D03*
Y80000D03*
X1740000Y140000D03*
X1760000Y120000D03*
X1740000D03*
X1720000Y140000D03*
Y120000D03*
X1728500Y249500D03*
X1746600Y240561D03*
X1760486Y217441D03*
X1763500Y288000D03*
X1720000Y300000D03*
Y280000D03*
Y340000D03*
X1760000D03*
X1740000Y320000D03*
X1760000Y440000D03*
Y420000D03*
Y500000D03*
Y480000D03*
Y460000D03*
X1740000Y540000D03*
X1760000D03*
Y520000D03*
X1721710Y516409D03*
X1745000Y670000D03*
Y690000D03*
Y660000D03*
X1730000Y690000D03*
Y670000D03*
Y730000D03*
Y710000D03*
X1735000Y785000D03*
X1730000Y775000D03*
Y750000D03*
X1725000Y800000D03*
X1718000Y876000D03*
X1759884Y969161D03*
X1742001Y965464D03*
X1755000Y1045000D03*
X1725000D03*
X1745000Y1100000D03*
X1759055Y1113504D03*
X1736725Y1123446D03*
X1748100Y1142673D03*
X1736871Y1158178D03*
X1736941Y1141871D03*
X1728000Y1204500D03*
X1720000Y1320000D03*
X1760000D03*
X1753000Y1302000D03*
X1764783Y1369303D03*
X1754783D03*
X1744783D03*
X1734783D03*
X1724783D03*
X1749783D03*
X1759783D03*
X1719783D03*
X1729783D03*
X1739783D03*
X1778030Y5500D03*
X1793030D03*
X1803030D03*
X1813030D03*
X1808030D03*
X1798030D03*
X1783030D03*
X1788030D03*
X1773030D03*
X1768030D03*
X1780000Y60000D03*
Y40000D03*
X1800000Y100000D03*
Y80000D03*
X1780000Y100000D03*
Y80000D03*
X1800000Y120000D03*
X1780000D03*
X1785956Y141870D03*
X1804350Y162661D03*
X1801988Y183904D03*
X1808050Y172661D03*
X1812350Y195261D03*
X1774456Y207992D03*
Y198543D03*
X1778956Y195492D03*
Y180492D03*
X1775140Y165728D03*
X1778956Y245492D03*
Y235492D03*
X1799350Y266161D03*
X1795350Y299661D03*
X1801850D03*
X1809850D03*
X1810850Y264661D03*
X1778956Y275492D03*
Y265492D03*
X1785956Y314114D03*
X1800000Y440000D03*
X1780000D03*
X1800000Y500000D03*
X1780000D03*
X1800000Y480000D03*
Y460000D03*
X1780000Y480000D03*
Y460000D03*
X1800000Y540000D03*
X1780000D03*
X1800000Y520000D03*
X1780000D03*
X1800000Y560000D03*
X1785956Y594626D03*
X1800650Y636417D03*
X1808050Y625417D03*
X1804350Y615417D03*
X1812350Y648017D03*
X1778956Y648248D03*
Y633248D03*
Y618248D03*
X1774456Y670197D03*
X1778956Y688248D03*
X1774456Y660748D03*
Y651299D03*
X1799326Y717506D03*
X1811474Y717423D03*
X1778956Y728248D03*
Y718248D03*
Y698248D03*
X1766721Y716500D03*
X1795468Y752594D03*
X1801968D03*
X1809968D03*
X1785956Y766870D03*
X1773500Y879500D03*
X1771000Y944500D03*
X1799000Y945500D03*
X1788361Y964676D03*
X1799051Y963346D03*
X1785956Y1047382D03*
X1808050Y1078173D03*
X1800750Y1067973D03*
X1778956Y1071004D03*
X1800650Y1089173D03*
X1811968Y1100773D03*
X1774456Y1122953D03*
Y1104055D03*
X1778956Y1101004D03*
Y1086004D03*
X1799350Y1171673D03*
X1810850Y1170173D03*
X1778956Y1171004D03*
Y1151004D03*
Y1141004D03*
X1795350Y1205173D03*
X1801850D03*
X1809850D03*
X1785956Y1219626D03*
X1778956Y1181004D03*
X1772111Y1232695D03*
X1804783Y1369303D03*
X1794783D03*
X1784783D03*
X1774783D03*
X1799783D03*
X1809783D03*
X1769783D03*
X1779783D03*
X1789783D03*
X1843030Y5500D03*
X1853030D03*
X1863030D03*
X1838030D03*
X1858030D03*
X1848030D03*
X1823030D03*
X1833030D03*
X1828030D03*
X1818030D03*
X1860000Y60000D03*
Y80000D03*
Y100000D03*
X1840000D03*
X1820000D03*
X1860000Y140000D03*
Y120000D03*
X1840000D03*
X1820000Y140000D03*
Y120000D03*
X1856219Y212661D03*
X1841169Y254661D03*
X1840000Y340000D03*
Y320000D03*
X1860000D03*
X1820000D03*
Y440000D03*
Y480000D03*
Y460000D03*
X1840000Y540000D03*
X1820000D03*
X1845545Y516536D03*
X1831330Y517279D03*
X1840000Y580000D03*
X1820000D03*
X1840000Y560000D03*
X1820000D03*
X1862200Y686700D03*
X1856219Y665417D03*
X1850000Y745000D03*
X1837576Y707417D03*
X1820000Y780000D03*
X1857363Y1002625D03*
X1845363D03*
X1849363D03*
X1861363D03*
X1853363D03*
X1856437Y1106400D03*
X1850532Y1153286D03*
X1836231Y1140669D03*
X1860000Y1320000D03*
X1854783Y1369303D03*
X1844783D03*
X1834783D03*
X1824783D03*
X1814783D03*
X1849783D03*
X1859783D03*
X1819783D03*
X1829783D03*
X1839783D03*
X1878030Y5500D03*
X1883030D03*
X1873030D03*
X1868030D03*
X1909030D03*
X1888030D03*
X1880000Y60000D03*
X1900000D03*
X1880000Y80000D03*
X1900000D03*
Y100000D03*
X1880000D03*
X1900000Y120000D03*
X1880000Y140000D03*
Y120000D03*
X1910169Y141870D03*
X1898669Y207992D03*
Y198543D03*
X1903169Y195492D03*
Y180492D03*
Y165492D03*
X1885204Y184345D03*
X1873500Y219000D03*
X1865169Y247161D03*
Y234661D03*
X1903169Y245492D03*
X1898669Y217441D03*
X1903169Y235492D03*
X1881088Y296184D03*
X1903169Y275492D03*
Y265492D03*
X1880969Y276861D03*
X1880000Y340000D03*
Y320000D03*
X1910169Y314114D03*
X1890000Y400000D03*
Y380000D03*
Y360000D03*
Y440000D03*
Y420000D03*
X1910169Y594626D03*
X1903169Y648248D03*
Y633248D03*
Y618248D03*
X1885300Y636800D03*
X1898669Y670197D03*
X1903169Y688248D03*
X1898669Y660748D03*
Y651299D03*
X1903169Y728248D03*
Y718248D03*
Y698248D03*
X1880969Y729617D03*
X1865169Y699917D03*
X1880000Y780000D03*
X1910169Y766870D03*
X1887169Y752917D03*
X1892443Y894350D03*
X1884200Y895000D03*
X1865363Y1002625D03*
X1868100Y1055410D03*
X1903169Y1071004D03*
X1910169Y1047382D03*
X1898669Y1122953D03*
Y1113504D03*
Y1104055D03*
X1903169Y1101004D03*
Y1086004D03*
X1863131Y1133108D03*
X1903169Y1171004D03*
X1903100Y1149700D03*
X1903169Y1141004D03*
X1864352Y1153308D03*
X1871174Y1138730D03*
X1887169Y1205673D03*
X1910169Y1219626D03*
X1903169Y1181004D03*
X1880969Y1182373D03*
X1900000Y1260000D03*
Y1280000D03*
Y1320000D03*
Y1300000D03*
X1904783Y1369303D03*
X1894783D03*
X1884783D03*
X1874783D03*
X1864783D03*
X1899783D03*
X1909783D03*
X1869783D03*
X1879783D03*
X1889783D03*
X1929343Y16525D03*
Y11525D03*
Y6525D03*
X1914030Y5500D03*
X1919030D03*
X1924030D03*
X1920000Y60000D03*
X1929343Y46525D03*
Y41525D03*
Y36525D03*
Y31525D03*
Y26525D03*
Y21525D03*
Y66525D03*
Y61525D03*
Y56525D03*
Y51525D03*
X1920000Y80000D03*
Y100000D03*
X1929343Y116525D03*
Y111525D03*
Y106525D03*
Y101525D03*
Y96525D03*
Y91525D03*
Y86525D03*
Y81525D03*
Y76525D03*
Y71525D03*
X1920000Y120000D03*
X1929343Y121525D03*
Y126525D03*
Y136525D03*
Y146525D03*
Y156525D03*
Y161525D03*
Y151525D03*
Y141525D03*
Y131525D03*
Y176525D03*
Y186525D03*
Y196525D03*
Y206525D03*
Y166525D03*
Y211525D03*
Y201525D03*
Y191525D03*
Y181525D03*
Y171525D03*
Y226525D03*
Y236525D03*
Y246525D03*
Y256525D03*
Y216525D03*
Y261525D03*
Y251525D03*
Y241525D03*
Y231525D03*
Y221525D03*
Y276525D03*
Y286525D03*
Y296525D03*
Y306525D03*
Y266525D03*
Y301525D03*
Y291525D03*
Y281525D03*
Y271525D03*
Y326525D03*
Y336525D03*
Y346525D03*
Y356525D03*
Y316525D03*
Y351525D03*
Y341525D03*
Y331525D03*
Y321525D03*
Y311525D03*
Y376525D03*
Y386525D03*
Y396525D03*
Y406525D03*
Y366525D03*
Y401525D03*
Y391525D03*
Y381525D03*
Y371525D03*
Y361525D03*
Y426525D03*
Y436525D03*
Y446525D03*
Y416525D03*
Y451525D03*
Y441525D03*
Y431525D03*
Y421525D03*
Y411525D03*
Y476525D03*
Y486525D03*
Y496525D03*
Y456525D03*
Y466525D03*
Y501525D03*
Y491525D03*
Y481525D03*
Y471525D03*
Y461525D03*
Y526525D03*
Y536525D03*
Y546525D03*
Y506525D03*
Y516525D03*
Y551525D03*
Y541525D03*
Y531525D03*
Y521525D03*
Y511525D03*
Y576525D03*
Y586525D03*
Y596525D03*
Y556525D03*
Y566525D03*
Y591525D03*
Y581525D03*
Y571525D03*
Y561525D03*
Y626525D03*
Y636525D03*
Y646525D03*
Y606525D03*
Y616525D03*
Y641525D03*
Y631525D03*
Y621525D03*
Y611525D03*
Y601525D03*
Y676525D03*
Y686525D03*
Y696525D03*
Y656525D03*
Y666525D03*
Y691525D03*
Y681525D03*
Y671525D03*
Y661525D03*
Y651525D03*
Y726525D03*
Y736525D03*
Y706525D03*
Y716525D03*
Y741525D03*
Y731525D03*
Y721525D03*
Y711525D03*
Y701525D03*
Y776525D03*
Y786525D03*
Y746525D03*
Y756525D03*
Y766525D03*
Y791525D03*
Y781525D03*
Y771525D03*
Y761525D03*
Y751525D03*
Y826525D03*
Y836525D03*
Y796525D03*
Y806525D03*
Y816525D03*
Y841525D03*
Y831525D03*
Y821525D03*
Y811525D03*
Y801525D03*
Y876525D03*
Y886525D03*
Y846525D03*
Y856525D03*
Y866525D03*
Y881525D03*
Y871525D03*
Y861525D03*
Y851525D03*
Y926525D03*
Y896525D03*
Y906525D03*
Y916525D03*
Y931525D03*
Y921525D03*
Y911525D03*
Y901525D03*
Y891525D03*
Y936525D03*
Y973863D03*
Y978863D03*
Y983863D03*
Y951525D03*
Y956525D03*
Y961525D03*
Y966525D03*
Y946525D03*
Y941525D03*
Y988863D03*
Y993863D03*
Y998863D03*
Y1003863D03*
Y1008863D03*
Y1033863D03*
Y1028863D03*
Y1023863D03*
Y1018863D03*
Y1013863D03*
Y1073863D03*
Y1083863D03*
Y1043863D03*
Y1053863D03*
Y1063863D03*
Y1078863D03*
Y1068863D03*
Y1058863D03*
Y1048863D03*
Y1038863D03*
Y1123863D03*
Y1093863D03*
Y1103863D03*
Y1113863D03*
Y1128863D03*
Y1118863D03*
Y1108863D03*
Y1098863D03*
Y1088863D03*
Y1173863D03*
Y1133863D03*
Y1143863D03*
Y1153863D03*
Y1163863D03*
Y1178863D03*
Y1168863D03*
Y1158863D03*
Y1148863D03*
Y1138863D03*
Y1223863D03*
Y1183863D03*
Y1193863D03*
Y1203863D03*
Y1213863D03*
Y1228863D03*
Y1218863D03*
Y1208863D03*
Y1198863D03*
Y1188863D03*
X1920000Y1260000D03*
X1929343Y1273863D03*
Y1233863D03*
Y1243863D03*
Y1253863D03*
Y1263863D03*
Y1268863D03*
Y1258863D03*
Y1248863D03*
Y1238863D03*
X1920000Y1280000D03*
Y1320000D03*
Y1300000D03*
X1929343Y1323863D03*
Y1283863D03*
Y1293863D03*
Y1303863D03*
Y1313863D03*
Y1318863D03*
Y1308863D03*
Y1298863D03*
Y1288863D03*
Y1278863D03*
Y1333863D03*
Y1343863D03*
Y1353863D03*
X1924783Y1369303D03*
X1914783D03*
X1919783D03*
X1929343Y1358863D03*
Y1348863D03*
Y1338863D03*
Y1328863D03*
Y1363863D03*
G54D28*
X188706Y941328D03*
X194206D03*
X260703Y529168D03*
X255203D03*
X702483Y945989D03*
X730882Y888502D03*
X716233Y868219D03*
X733422Y857828D03*
X721552Y951317D03*
X725852Y951067D03*
X763883Y907689D03*
X755883D03*
X750883Y903689D03*
X802102Y51075D03*
X799102Y48575D03*
X802102Y46075D03*
X799102Y43575D03*
X802102Y41075D03*
X868100Y685600D03*
X871700D03*
X875300D03*
X884600Y688800D03*
X881000D03*
X877400D03*
X891000Y743500D03*
X870500Y762500D03*
X932294Y1379995D03*
X928194D03*
X1843731Y936066D03*
X1843811Y940067D03*
X1830665Y941751D03*
X1836165D03*
X1908107Y831894D03*
X1902607D03*
X1907999Y846368D03*
X1902499D03*
G54D23*
X111800Y987200D03*
Y983200D03*
X115800Y979200D03*
X119800Y971200D03*
Y975200D03*
Y979200D03*
X115800Y975200D03*
X119800Y987200D03*
Y983200D03*
X115800Y971200D03*
Y983200D03*
Y987200D03*
X119163Y959625D03*
X121914Y1003491D03*
X153263Y568725D03*
X146263D03*
X144263Y573225D03*
X138763Y568725D03*
X148763Y576225D03*
X188614Y591491D03*
X182500Y559200D03*
Y571200D03*
Y575200D03*
X178500D03*
Y571200D03*
X182500Y567200D03*
X186500Y559200D03*
Y563200D03*
Y567200D03*
X182500Y563200D03*
X186500Y575200D03*
Y571200D03*
X184017Y951112D03*
Y945612D03*
X198463Y945525D03*
Y951025D03*
X265392Y539225D03*
Y533725D03*
X250586Y533920D03*
Y539420D03*
X465346Y1122953D03*
X858632Y399200D03*
X855032D03*
Y395600D03*
X858632D03*
X855032Y392000D03*
X858632D03*
X852832Y406400D03*
Y402800D03*
X856432Y406400D03*
Y402800D03*
X852832Y410000D03*
X856432D03*
X1398493Y314114D03*
X1717681Y1006054D03*
X1712181Y1001554D03*
X1757600Y987200D03*
X1761600D03*
Y983200D03*
X1757600D03*
X1761600Y991200D03*
Y999200D03*
Y995200D03*
X1757600Y991200D03*
X1753600Y995200D03*
Y999200D03*
X1757600D03*
Y995200D03*
X1726681Y1001554D03*
X1719681D03*
X1722181Y1009054D03*
X1763714Y1015491D03*
X1840419Y945557D03*
Y951057D03*
X1825945Y945449D03*
Y950949D03*
G54D36*
X944882Y-63877D03*
G54D38*
X942126Y58465D03*
Y346457D03*
Y437598D03*
Y725590D03*
X1110236Y58465D03*
Y346457D03*
Y437598D03*
Y725590D03*
G54D33*
X496653Y80906D03*
X1465157D03*
G54D15*
X60540Y-85109D03*
X59536Y1573374D03*
X79000Y1301900D03*
X1826700Y77600D03*
X1865705Y1573374D03*
X1898432Y-93682D03*
X1908500Y1346800D03*
G54D12*
X15157Y474409D03*
X904921Y-25591D03*
X1894684Y474409D03*
G54D18*
X80019Y51968D03*
X127263Y20472D03*
X631200Y51968D03*
X678444Y20472D03*
X1250689Y51969D03*
X1297933Y20472D03*
X1801870Y51969D03*
X1849114Y20472D03*
G54D10*
X15157Y21653D03*
X904921Y564960D03*
X1894685Y21654D03*
G54D34*
X496653Y110552D03*
X1465157D03*
G54D26*
X173228Y1062992D03*
X421653Y1141732D03*
X670079Y1062992D03*
X1343701D03*
X1592126Y1141732D03*
X1840551Y1062992D03*
G54D35*
X503248Y829921D03*
X1673917D03*
G54D13*
X31496Y882677D03*
X168307Y646457D03*
X660236D03*
X718110Y820866D03*
X1366142Y646457D03*
X1462992Y866929D03*
X1602756Y646457D03*
X1903346Y803937D03*
G54D39*
X975787Y-25590D03*
G54D17*
X103642Y36220D03*
X654822D03*
X1274311D03*
X1825492D03*
G54D27*
X173228Y1114173D03*
X670079D03*
X1343700D03*
X1840551D03*
G54D40*
X975786Y564960D03*
G54D44*
X1104527Y1630792D03*
G54D16*
X47000Y1107500D03*
X549279Y513331D03*
X525579Y538331D03*
X557279Y513331D03*
X533879Y566031D03*
X548767Y556819D03*
X520579Y553231D03*
X517499Y576931D03*
X575700Y528831D03*
X563279Y506731D03*
X704399Y626799D03*
Y618399D03*
Y622599D03*
X748500Y1287500D03*
X752000Y1197500D03*
X756000Y1225500D03*
X770000Y1231500D03*
X769500Y1283500D03*
X827000Y1168000D03*
X802500Y1194500D03*
X807500D03*
X812500D03*
X810000Y1191500D03*
X805000D03*
X870163Y836153D03*
X865663Y834403D03*
X895869Y932822D03*
X898920Y1020000D03*
X906000Y1222000D03*
X924500Y1236000D03*
X932500Y1493200D03*
X926500Y1499700D03*
X918500D03*
X906000Y1543700D03*
X962900Y905000D03*
X953967Y933635D03*
X948942Y974655D03*
X961134Y976191D03*
X946138Y1006299D03*
X944921Y1515200D03*
X986614Y1619764D03*
X974016D03*
Y1597126D03*
X986614D03*
X974016Y1591220D03*
Y1603031D03*
Y1613858D03*
X986614Y1591220D03*
Y1613858D03*
Y1603031D03*
X974016Y1625669D03*
X986614D03*
X1031563Y852453D03*
X1025774Y1001538D03*
X992994Y1005740D03*
X1037000Y1067100D03*
X1032500D03*
X1017000Y1093950D03*
X1021200Y1094300D03*
X1002362Y1597126D03*
X1014961D03*
X1030709D03*
X1002362Y1591220D03*
Y1603031D03*
X1014961Y1591220D03*
Y1603031D03*
X1030709Y1591220D03*
Y1603031D03*
X1076000Y-10500D03*
X1062854Y83434D03*
X1053200Y901703D03*
X1043882Y901568D03*
X1082500Y1067100D03*
X1073500D03*
X1064500Y1096150D03*
X1068700Y1096600D03*
X1066750Y1224035D03*
X1079250D03*
X1066750Y1209862D03*
X1079250D03*
X1066750Y1216949D03*
X1079250D03*
X1066750Y1231122D03*
X1079250D03*
X1066750Y1238209D03*
X1079250D03*
X1066750Y1245295D03*
X1079250D03*
X1066750Y1301988D03*
X1079250D03*
X1066750Y1309075D03*
X1079250D03*
X1066750Y1316161D03*
X1079250D03*
X1066750Y1323248D03*
X1079250D03*
X1066750Y1294902D03*
X1079250D03*
X1066750Y1330335D03*
X1079250D03*
X1066750Y1387028D03*
X1079250D03*
X1066750Y1394114D03*
X1079250D03*
X1066750Y1401201D03*
X1079250D03*
X1066750Y1408287D03*
X1079250D03*
X1066750Y1415374D03*
X1079250D03*
X1066750Y1379941D03*
X1079250D03*
X1043307Y1597126D03*
Y1591220D03*
Y1603031D03*
X1100847Y905617D03*
X1105847D03*
X1110847D03*
X1108347Y902617D03*
X1103347D03*
X1119700Y1067200D03*
X1124500D03*
X1101580Y1091120D03*
X1107100Y1096050D03*
X1111600Y1097800D03*
X1090818Y1531620D03*
X1092927Y1558887D03*
Y1555087D03*
X1095938Y1531620D03*
Y1535420D03*
X1090818D03*
X1096547Y1558887D03*
Y1555087D03*
X1265250Y167823D03*
X1252750D03*
X1376963D03*
X1355700Y587600D03*
X1359700D03*
X1389463Y167823D03*
G54D25*
X127988Y194242D03*
Y181742D03*
Y634498D03*
Y646998D03*
Y1087254D03*
Y1099754D03*
X252200Y194242D03*
Y181742D03*
Y634498D03*
Y646998D03*
Y1087254D03*
Y1099754D03*
X322545Y72845D03*
X376413Y194242D03*
Y181742D03*
Y634498D03*
Y646998D03*
Y1087254D03*
Y1099754D03*
X453473Y1089300D03*
X500625Y194242D03*
Y181742D03*
Y634498D03*
Y646998D03*
X460673Y1071976D03*
X460873Y1077526D03*
X500625Y1087254D03*
Y1099754D03*
X624838Y194242D03*
Y181742D03*
Y634498D03*
Y646998D03*
Y1087254D03*
Y1099754D03*
X696787Y580633D03*
X749051Y194242D03*
Y181742D03*
Y634498D03*
Y646998D03*
X708683Y876958D03*
X749051Y1087254D03*
Y1099754D03*
X928600Y-115200D03*
X986713Y-115570D03*
X971713D03*
X1046713D03*
X1076713D03*
X1117535Y-115157D03*
X1091089Y988592D03*
X1105262D03*
X1119435D03*
X1133609D03*
X1095026Y995678D03*
X1109199D03*
X1123372D03*
X1091089Y1002765D03*
X1105262D03*
X1119435D03*
X1133609D03*
X1095026Y1009852D03*
X1109199D03*
X1123372D03*
X1091089Y1016938D03*
X1105262D03*
X1119435D03*
X1133609D03*
X1095026Y1024025D03*
X1109199D03*
X1123372D03*
X1091089Y1031111D03*
X1105262D03*
X1119435D03*
X1133609D03*
X1095026Y1038198D03*
X1109199D03*
X1123372D03*
X1091089Y1160257D03*
Y1174430D03*
X1105262Y1160257D03*
Y1174430D03*
X1119435Y1160257D03*
Y1174430D03*
X1133609Y1160257D03*
Y1174430D03*
X1095026Y1167343D03*
X1109199D03*
X1123372D03*
X1091089Y1188603D03*
Y1202776D03*
Y1216949D03*
X1105262Y1188603D03*
Y1202776D03*
Y1216949D03*
X1119435Y1188603D03*
Y1202776D03*
Y1216949D03*
X1133609Y1188603D03*
Y1202776D03*
Y1216949D03*
X1095026Y1181516D03*
Y1195690D03*
Y1209863D03*
Y1224036D03*
X1109199Y1181516D03*
Y1195690D03*
Y1209863D03*
Y1224036D03*
X1123372Y1181516D03*
Y1195690D03*
Y1209863D03*
Y1224036D03*
X1091089Y1231123D03*
Y1245296D03*
Y1259469D03*
Y1273642D03*
X1105262Y1231123D03*
Y1245296D03*
Y1259469D03*
Y1273642D03*
X1119435Y1231123D03*
Y1245296D03*
Y1259469D03*
Y1273642D03*
X1133609Y1231123D03*
Y1245296D03*
Y1259469D03*
Y1273642D03*
X1095026Y1238209D03*
Y1252382D03*
Y1266556D03*
X1109199Y1238209D03*
Y1252382D03*
Y1266556D03*
X1123372Y1238209D03*
Y1252382D03*
Y1266556D03*
X1091089Y1287816D03*
Y1301989D03*
Y1316162D03*
X1105262Y1287816D03*
Y1301989D03*
Y1316162D03*
X1119435Y1287816D03*
Y1301989D03*
Y1316162D03*
X1133609Y1287816D03*
Y1301989D03*
Y1316162D03*
X1095026Y1280729D03*
Y1294902D03*
Y1309075D03*
Y1323249D03*
X1109199Y1280729D03*
Y1294902D03*
Y1309075D03*
Y1323249D03*
X1123372Y1280729D03*
Y1294902D03*
Y1309075D03*
Y1323249D03*
X1091089Y1330335D03*
Y1344508D03*
Y1358682D03*
Y1372855D03*
X1105262Y1330335D03*
Y1344508D03*
Y1358682D03*
Y1372855D03*
X1119435Y1330335D03*
Y1344508D03*
Y1358682D03*
Y1372855D03*
X1133609Y1330335D03*
Y1344508D03*
Y1358682D03*
Y1372855D03*
X1095026Y1337422D03*
Y1351595D03*
Y1365768D03*
X1109199Y1337422D03*
Y1351595D03*
Y1365768D03*
X1123372Y1337422D03*
Y1351595D03*
Y1365768D03*
X1091089Y1387028D03*
Y1401201D03*
X1105262Y1387028D03*
Y1401201D03*
X1119435Y1387028D03*
Y1401201D03*
X1133609Y1387028D03*
Y1401201D03*
X1095026Y1379942D03*
Y1394115D03*
Y1408288D03*
X1109199Y1379942D03*
Y1394115D03*
Y1408288D03*
X1123372Y1379942D03*
Y1394115D03*
Y1408288D03*
X1101457Y1588583D03*
X1119685D03*
X1108150D03*
X1126378D03*
X1182590Y254388D03*
X1174037Y281343D03*
X1278500Y634498D03*
Y646998D03*
Y1087254D03*
Y1099754D03*
X1402713Y181742D03*
Y194242D03*
Y634498D03*
Y646998D03*
Y1087254D03*
Y1099754D03*
X1526925Y181742D03*
Y194242D03*
Y634498D03*
Y646998D03*
Y1087254D03*
Y1099754D03*
X1651138Y181742D03*
Y194242D03*
Y634498D03*
Y646998D03*
Y1087254D03*
Y1099754D03*
X1725350Y634498D03*
Y646998D03*
X1775350Y181742D03*
Y194242D03*
Y1087254D03*
Y1099754D03*
X1859017Y161725D03*
X1859117Y167375D03*
X1851717Y179075D03*
X1858917Y614481D03*
X1859117Y620131D03*
X1851717Y635331D03*
X1848491Y819787D03*
Y823787D03*
Y815787D03*
Y807787D03*
Y811787D03*
X1899563Y181742D03*
Y194242D03*
Y634498D03*
Y646998D03*
X1871000Y1073300D03*
X1899563Y1087254D03*
Y1099754D03*
X1863700Y1085000D03*
G54D29*
X184295Y1009469D03*
Y1014969D03*
X198741Y1014882D03*
Y1009382D03*
X265275Y596896D03*
X250974Y597308D03*
X265275Y602396D03*
X250974Y602808D03*
X429724Y63977D03*
X443898D03*
X458071D03*
X436811Y67914D03*
X450984D03*
X429724Y92323D03*
Y106496D03*
Y78150D03*
X436811Y82087D03*
X450984D03*
X443898Y92323D03*
X458071D03*
X436811Y96260D03*
X450984D03*
X443898Y106496D03*
X458071D03*
X436811Y110433D03*
X450984D03*
X443898Y78150D03*
X458071D03*
X429724Y120670D03*
X443898D03*
X458071D03*
X465157Y67914D03*
X472244Y63977D03*
X479331Y67914D03*
X465157Y82087D03*
Y96260D03*
Y110433D03*
X479331Y82087D03*
X472244Y92323D03*
X479331Y96260D03*
X472244Y106496D03*
X479331Y110433D03*
X472244Y78150D03*
Y120670D03*
X514764Y63977D03*
X550197Y67914D03*
X536024D03*
X521850D03*
X543110Y63977D03*
X528937D03*
X557283D03*
X514764Y106496D03*
Y92323D03*
Y78150D03*
X550197Y110433D03*
X536024D03*
X521850D03*
X543110Y106496D03*
X528937D03*
X550197Y96260D03*
X536024D03*
X521850D03*
X543110Y92323D03*
X528937D03*
X550197Y82087D03*
X536024D03*
X521850D03*
X543110Y78150D03*
X528937D03*
X557283Y106496D03*
Y92323D03*
Y78150D03*
X514764Y120670D03*
X543110D03*
X528937D03*
X557283D03*
X564370Y67914D03*
Y110433D03*
Y96260D03*
Y82087D03*
X1398228Y63977D03*
X1412402D03*
X1426575D03*
X1405315Y67914D03*
X1419488D03*
X1398228Y92323D03*
Y106496D03*
Y78150D03*
X1405315Y82087D03*
X1419488D03*
X1412402Y92323D03*
X1426575D03*
X1405315Y96260D03*
X1419488D03*
X1412402Y106496D03*
X1426575D03*
X1405315Y110433D03*
X1419488D03*
X1412402Y78150D03*
X1426575D03*
X1398228Y120670D03*
X1412402D03*
X1426575D03*
X1433661Y67914D03*
X1440748Y63977D03*
X1447835Y67914D03*
X1433661Y82087D03*
Y96260D03*
Y110433D03*
X1447835Y82087D03*
X1440748Y92323D03*
X1447835Y96260D03*
X1440748Y106496D03*
X1447835Y110433D03*
X1440748Y78150D03*
Y120670D03*
X1483268Y63977D03*
X1518701Y67914D03*
X1504528D03*
X1490354D03*
X1511614Y63977D03*
X1497441D03*
X1483268Y106496D03*
Y92323D03*
Y78150D03*
X1518701Y110433D03*
X1504528D03*
X1490354D03*
X1511614Y106496D03*
X1497441D03*
X1518701Y96260D03*
X1504528D03*
X1490354D03*
X1511614Y92323D03*
X1497441D03*
X1518701Y82087D03*
X1504528D03*
X1490354D03*
X1511614Y78150D03*
X1497441D03*
X1483268Y120670D03*
X1511614D03*
X1497441D03*
X1532874Y67914D03*
X1525787Y63977D03*
X1532874Y110433D03*
X1525787Y106496D03*
X1532874Y96260D03*
X1525787Y92323D03*
X1532874Y82087D03*
X1525787Y78150D03*
Y120670D03*
X1825971Y1015512D03*
Y1010012D03*
X1840445Y1015620D03*
Y1010120D03*
X1912551Y836444D03*
Y841944D03*
G54D30*
X188552Y1019166D03*
X194052D03*
X255410Y607833D03*
X260910D03*
X1850151Y835119D03*
X1850177Y838746D03*
X1838239Y831626D03*
X1845579Y831731D03*
X1838311Y827911D03*
X1845651Y828016D03*
X1860276Y916059D03*
Y912059D03*
X1835895Y1020064D03*
X1830395D03*
X1872276Y916059D03*
X1876276D03*
Y920059D03*
X1872276D03*
X1868276Y916059D03*
X1864276Y912059D03*
X1868276D03*
X1864276Y916059D03*
X1876276Y912059D03*
X1872276D03*
X1875801Y946796D03*
X1875769Y951122D03*
X1880122Y954062D03*
X1880383Y950341D03*
G36*
G01X149668Y380135D02*
G02X112735I-18466J-14781D01*
G03X119308Y392599I-29176J23351D01*
G02X143095I11894J-3623D01*
G03X149668Y380135I35749J10887D01*
G37*
G36*
G01X149667Y832891D02*
G02X112734I-18466J-14781D01*
G03X119307Y845355I-29176J23351D01*
G02X143094I11894J-3623D01*
G03X149667Y832891I35749J10887D01*
G37*
G36*
G01X149668Y1285647D02*
G02X112735I-18466J-14781D01*
G03X119308Y1298111I-29176J23351D01*
G02X143095I11894J-3623D01*
G03X149668Y1285647I35749J10887D01*
G37*
G36*
G01X397699Y380135D02*
G02X360766I-18467J-14781D01*
G03X367339Y392599I-29176J23351D01*
G02X391126I11894J-3623D01*
G03X397699Y380135I35749J10887D01*
G37*
G36*
G01Y832891D02*
G02X360766I-18467J-14781D01*
G03X367339Y845355I-29176J23351D01*
G02X391126I11894J-3623D01*
G03X397699Y832891I35749J10887D01*
G37*
G36*
G01Y1285647D02*
G02X360766I-18467J-14781D01*
G03X367339Y1298111I-29176J23351D01*
G02X391126I11894J-3623D01*
G03X397699Y1285647I35749J10887D01*
G37*
G36*
G01X645730Y380135D02*
G02X608797I-18466J-14781D01*
G03X615370Y392599I-29176J23351D01*
G02X639157I11893J-3623D01*
G03X645730Y380135I35749J10887D01*
G37*
G36*
G01Y832891D02*
G02X608797I-18466J-14781D01*
G03X615370Y845355I-29176J23351D01*
G02X639157I11893J-3623D01*
G03X645730Y832891I35749J10887D01*
G37*
G36*
G01Y1285647D02*
G02X608797I-18466J-14781D01*
G03X615370Y1298111I-29176J23351D01*
G02X639157I11893J-3623D01*
G03X645730Y1285647I35749J10887D01*
G37*
G36*
G01X814924Y265984D02*
G02X777991I-18467J-14781D01*
G03X784564Y278448I-29176J23351D01*
G02X808351I11893J-3623D01*
G03X814924Y265984I35749J10887D01*
G37*
G36*
G01Y738425D02*
G02X777991I-18467J-14781D01*
G03X784564Y750889I-29176J23351D01*
G02X808351I11893J-3623D01*
G03X814924Y738425I35749J10887D01*
G37*
G36*
G01X979885Y1090394D02*
G02X942952I-18467J-14781D01*
G03X949525Y1102858I-29176J23351D01*
G02X973312I11894J-3623D01*
G03X979885Y1090394I35749J10887D01*
G37*
G36*
G01Y1432913D02*
G02X942952I-18467J-14781D01*
G03X949525Y1445377I-29176J23351D01*
G02X973312I11894J-3623D01*
G03X979885Y1432913I35749J10887D01*
G37*
G36*
G01X1200357Y558898D02*
G02X1163424I-18467J-14781D01*
G03X1169997Y571362I-29176J23351D01*
G02X1193784I11894J-3623D01*
G03X1200357Y558898I35749J10887D01*
G37*
G36*
G01X1200337Y972261D02*
G02X1163404I-18467J-14781D01*
G03X1169977Y984725I-29176J23351D01*
G02X1193764I11894J-3623D01*
G03X1200337Y972261I35749J10887D01*
G37*
G36*
G01X1200357Y1562835D02*
G02X1163424I-18467J-14781D01*
G03X1169997Y1575299I-29176J23351D01*
G02X1193784I11894J-3623D01*
G03X1200357Y1562835I35749J10887D01*
G37*
G36*
G01X1320337Y380135D02*
G02X1283404I-18467J-14781D01*
G03X1289977Y392599I-29176J23351D01*
G02X1313764I11894J-3623D01*
G03X1320337Y380135I35749J10887D01*
G37*
G36*
G01Y832891D02*
G02X1283404I-18467J-14781D01*
G03X1289977Y845355I-29176J23351D01*
G02X1313764I11894J-3623D01*
G03X1320337Y832891I35749J10887D01*
G37*
G36*
G01Y1285647D02*
G02X1283404I-18467J-14781D01*
G03X1289977Y1298111I-29176J23351D01*
G02X1313764I11894J-3623D01*
G03X1320337Y1285647I35749J10887D01*
G37*
G36*
G01X1568368Y380135D02*
G02X1531435I-18467J-14781D01*
G03X1538008Y392599I-29176J23351D01*
G02X1561795I11894J-3623D01*
G03X1568368Y380135I35749J10887D01*
G37*
G36*
G01Y832891D02*
G02X1531435I-18467J-14781D01*
G03X1538008Y845355I-29176J23351D01*
G02X1561795I11894J-3623D01*
G03X1568368Y832891I35749J10887D01*
G37*
G36*
G01Y1285647D02*
G02X1531435I-18467J-14781D01*
G03X1538008Y1298111I-29176J23351D01*
G02X1561795I11894J-3623D01*
G03X1568368Y1285647I35749J10887D01*
G37*
G36*
G01X1816400Y380135D02*
G02X1779467I-18466J-14781D01*
G03X1786040Y392599I-29176J23351D01*
G02X1809827I11894J-3623D01*
G03X1816400Y380135I35749J10887D01*
G37*
G36*
G01Y832891D02*
G02X1779467I-18466J-14781D01*
G03X1786040Y845355I-29176J23351D01*
G02X1809827I11894J-3623D01*
G03X1816400Y832891I35749J10887D01*
G37*
G36*
G01Y1285647D02*
G02X1779467I-18466J-14781D01*
G03X1786040Y1298111I-29176J23351D01*
G02X1809827I11894J-3623D01*
G03X1816400Y1285647I35749J10887D01*
G37*
%LPC*%
G75*
G54D45*
G01X363248Y-425196D02*
Y-505196D01*
G01D02*
X1639148D01*
G01X359248Y-409196D02*
G02I-12000J0D01*
G01X354098D02*
G02I-6850J0D01*
G01X347248Y-425196D02*
Y-393196D01*
G01X363248Y-425196D02*
X1639148D01*
G01X363248Y-460696D02*
X1639148D01*
G01X363248Y-409196D02*
X331248D01*
G01X720748Y-425196D02*
Y-505196D01*
G01X858248Y-425196D02*
Y-505196D01*
G01X973248Y-425196D02*
Y-505196D01*
G01X1271648Y-425196D02*
Y-505196D01*
G01X1441648Y-425196D02*
Y-505196D01*
G01X1639148Y-425196D02*
Y-505196D01*
G01X1667148Y-409196D02*
G02I-12000J0D01*
G01X1661998D02*
G02I-6850J0D01*
G01X1655148Y-425196D02*
Y-393196D01*
G01X1671148Y-409196D02*
X1639148D01*
G54D46*
G01X394744Y-485863D02*
X395618Y-484988D01*
X396273Y-483530D01*
X396710Y-481487D01*
X396273Y-479738D01*
X395400Y-478571D01*
X393871Y-477696D01*
X387976D01*
Y-495196D01*
X395181D01*
X396710Y-494030D01*
X397583Y-492279D01*
X398020Y-490238D01*
X397583Y-488196D01*
X396273Y-486446D01*
X394744Y-485863D01*
X387976D01*
G01X407441Y-495196D02*
Y-483530D01*
G01Y-485863D02*
X408533Y-484696D01*
X409625Y-483821D01*
X411153Y-483530D01*
X412244Y-483821D01*
X413555Y-484696D01*
G01X423413Y-500446D02*
X424723Y-501029D01*
X426470Y-500446D01*
X427561Y-499280D01*
X428435Y-497821D01*
X429744Y-493155D01*
X432583Y-483530D01*
G01X425596D02*
X429744Y-493155D01*
G01X448991Y-484988D02*
X447463Y-483821D01*
X446153Y-483530D01*
X444406Y-484113D01*
X443096Y-485279D01*
X442223Y-487321D01*
X442004Y-489363D01*
X442223Y-491405D01*
X443096Y-493155D01*
X444406Y-494613D01*
X446153Y-495196D01*
X447681Y-494613D01*
X448991Y-493446D01*
G01X459723Y-487321D02*
X466710D01*
X466055Y-485279D01*
X464963Y-484113D01*
X463435Y-483530D01*
X461906Y-483821D01*
X460596Y-484696D01*
X459723Y-486738D01*
X459286Y-488488D01*
Y-490238D01*
X459723Y-491988D01*
X460815Y-493738D01*
X462125Y-494904D01*
X463653Y-495196D01*
X465181Y-494613D01*
X466710Y-492863D01*
G01X502801Y-479155D02*
X501491Y-478279D01*
X499963Y-477696D01*
X498216D01*
X496251Y-478571D01*
X494723Y-480029D01*
X493631Y-481780D01*
X492758Y-484696D01*
X492539Y-487321D01*
X492976Y-489946D01*
X493631Y-491696D01*
X494941Y-493446D01*
X496470Y-494613D01*
X497998Y-495196D01*
X499526D01*
X501055Y-494613D01*
X502365Y-493738D01*
X503457Y-492572D01*
G01X519428Y-495196D02*
Y-483530D01*
G01Y-485571D02*
X518555Y-484405D01*
X517244Y-483821D01*
X515716Y-483530D01*
X514188Y-484113D01*
X512878Y-485279D01*
X512004Y-487029D01*
X511568Y-489363D01*
X512004Y-491696D01*
X512878Y-493446D01*
X514188Y-494613D01*
X515716Y-495196D01*
X517244Y-494904D01*
X518555Y-494030D01*
X519428Y-492863D01*
G01X529286Y-495196D02*
Y-483530D01*
G01Y-486446D02*
X530160Y-484988D01*
X531470Y-483821D01*
X533216Y-483530D01*
X534744Y-483821D01*
X536055Y-484988D01*
X536710Y-487029D01*
Y-495196D01*
G01X545913Y-500446D02*
X547223Y-501029D01*
X548970Y-500446D01*
X550061Y-499280D01*
X550935Y-497821D01*
X552244Y-493155D01*
X555083Y-483530D01*
G01X548096D02*
X552244Y-493155D01*
G01X567998Y-495196D02*
X566688Y-494904D01*
X565378Y-493738D01*
X564504Y-491696D01*
X564068Y-489363D01*
X564504Y-487029D01*
X565378Y-484988D01*
X566688Y-483821D01*
X567998Y-483530D01*
X569308Y-483821D01*
X570618Y-484988D01*
X571491Y-487029D01*
X571710Y-489363D01*
X571491Y-491696D01*
X570618Y-493738D01*
X569308Y-494904D01*
X567998Y-495196D01*
G01X581786D02*
Y-483530D01*
G01Y-486446D02*
X582660Y-484988D01*
X583970Y-483821D01*
X585716Y-483530D01*
X587244Y-483821D01*
X588555Y-484988D01*
X589210Y-487029D01*
Y-495196D01*
G01X616350D02*
Y-477696D01*
X624646D01*
G01X621590Y-486154D02*
X616350D01*
G01X637998Y-495779D02*
X637561Y-495488D01*
Y-494904D01*
X637998Y-494613D01*
X638435Y-494904D01*
Y-495488D01*
X637998Y-495779D01*
G01X650695Y-495196D02*
Y-477696D01*
X655061D01*
X656808Y-478571D01*
X658118Y-479738D01*
X659210Y-481487D01*
X660083Y-483530D01*
X660301Y-486446D01*
X660083Y-489363D01*
X659210Y-491405D01*
X658118Y-493155D01*
X656808Y-494321D01*
X655061Y-495196D01*
X650695D01*
G01X668631D02*
Y-477696D01*
X673871D01*
X675618Y-478571D01*
X676928Y-480613D01*
X677365Y-482946D01*
X676928Y-485279D01*
X675836Y-487029D01*
X673871Y-487905D01*
X668631D01*
G01X692244Y-485863D02*
X693118Y-484988D01*
X693773Y-483530D01*
X694210Y-481487D01*
X693773Y-479738D01*
X692900Y-478571D01*
X691371Y-477696D01*
X685476D01*
Y-495196D01*
X692681D01*
X694210Y-494030D01*
X695083Y-492279D01*
X695520Y-490238D01*
X695083Y-488196D01*
X693773Y-486446D01*
X692244Y-485863D01*
X685476D01*
G01X501071Y-450196D02*
Y-432696D01*
X506748Y-447279D01*
X512425Y-432696D01*
Y-450196D01*
G01X524248D02*
X522938Y-449904D01*
X521628Y-448738D01*
X520754Y-446696D01*
X520318Y-444363D01*
X520754Y-442029D01*
X521628Y-439988D01*
X522938Y-438821D01*
X524248Y-438530D01*
X525558Y-438821D01*
X526868Y-439988D01*
X527741Y-442029D01*
X527960Y-444363D01*
X527741Y-446696D01*
X526868Y-448738D01*
X525558Y-449904D01*
X524248Y-450196D01*
G01X545678Y-432696D02*
Y-450196D01*
G01Y-447572D02*
X544805Y-449030D01*
X543494Y-449904D01*
X541966Y-450196D01*
X540220Y-449613D01*
X538910Y-448155D01*
X538036Y-446405D01*
X537818Y-444363D01*
X538036Y-442321D01*
X538910Y-440571D01*
X540220Y-439113D01*
X541966Y-438530D01*
X543494Y-438821D01*
X544586Y-439405D01*
X545678Y-440571D01*
G01X555973Y-442321D02*
X562960D01*
X562305Y-440279D01*
X561213Y-439113D01*
X559685Y-438530D01*
X558156Y-438821D01*
X556846Y-439696D01*
X555973Y-441738D01*
X555536Y-443488D01*
Y-445238D01*
X555973Y-446988D01*
X557065Y-448738D01*
X558375Y-449904D01*
X559903Y-450196D01*
X561431Y-449613D01*
X562960Y-447863D01*
G01X576748Y-450196D02*
Y-432696D01*
G01X754448Y-495196D02*
Y-477696D01*
X751828Y-481196D01*
G01Y-495196D02*
X757068D01*
G01X767800Y-487905D02*
X769328Y-485863D01*
X770638Y-484696D01*
X772385Y-484113D01*
X773913Y-484696D01*
X775005Y-485863D01*
X775878Y-487613D01*
X776096Y-489654D01*
X775878Y-491405D01*
X775005Y-493155D01*
X773694Y-494613D01*
X772166Y-495196D01*
X770420Y-494613D01*
X768891Y-492863D01*
X768018Y-490238D01*
X767800Y-487321D01*
X768236Y-483530D01*
X768891Y-481487D01*
X769983Y-479446D01*
X771511Y-477988D01*
X773040Y-477696D01*
X774568Y-478279D01*
X775660Y-479738D01*
G01X784645Y-491696D02*
X785954Y-493738D01*
X787701Y-494904D01*
X789666Y-495196D01*
X791413Y-494904D01*
X793160Y-493446D01*
X794251Y-491696D01*
X794470Y-489946D01*
X794033Y-487905D01*
X792505Y-486446D01*
X790976Y-485863D01*
X789011D01*
G01X790976D02*
X792286Y-484988D01*
X793378Y-483530D01*
X793815Y-481780D01*
X793378Y-480029D01*
X792286Y-478571D01*
X790321Y-477696D01*
X788356Y-477988D01*
X786391Y-479155D01*
G01X806948Y-495196D02*
Y-477696D01*
X804328Y-481196D01*
G01Y-495196D02*
X809568D01*
G01X819645Y-492572D02*
X820954Y-494030D01*
X822483Y-494904D01*
X824448Y-495196D01*
X826413Y-494613D01*
X827941Y-493446D01*
X829033Y-491405D01*
X829251Y-489071D01*
X828815Y-486738D01*
X827723Y-485279D01*
X826194Y-484113D01*
X824666Y-483821D01*
X823138Y-484113D01*
X821173Y-485279D01*
X821828Y-477696D01*
X827723D01*
G01X741331Y-450196D02*
Y-432696D01*
X746571D01*
X748318Y-433571D01*
X749628Y-435613D01*
X750065Y-437946D01*
X749628Y-440279D01*
X748536Y-442029D01*
X746571Y-442905D01*
X741331D01*
G01X768001Y-434155D02*
X766691Y-433279D01*
X765163Y-432696D01*
X763416D01*
X761451Y-433571D01*
X759923Y-435029D01*
X758831Y-436780D01*
X757958Y-439696D01*
X757739Y-442321D01*
X758176Y-444946D01*
X758831Y-446696D01*
X760141Y-448446D01*
X761670Y-449613D01*
X763198Y-450196D01*
X764726D01*
X766255Y-449613D01*
X767565Y-448738D01*
X768657Y-447572D01*
G01X782444Y-440863D02*
X783318Y-439988D01*
X783973Y-438530D01*
X784410Y-436487D01*
X783973Y-434738D01*
X783100Y-433571D01*
X781571Y-432696D01*
X775676D01*
Y-450196D01*
X782881D01*
X784410Y-449030D01*
X785283Y-447279D01*
X785720Y-445238D01*
X785283Y-443196D01*
X783973Y-441446D01*
X782444Y-440863D01*
X775676D01*
G01X791648Y-456029D02*
X804748D01*
G01X810676Y-450196D02*
Y-432696D01*
X820720Y-450196D01*
Y-432696D01*
G01X833198Y-450196D02*
X831451Y-449904D01*
X829923Y-448738D01*
X828613Y-446988D01*
X827739Y-444946D01*
X827303Y-442613D01*
Y-440279D01*
X827739Y-437946D01*
X828613Y-435904D01*
X829923Y-434155D01*
X831451Y-432988D01*
X833198Y-432696D01*
X834944Y-432988D01*
X836473Y-434155D01*
X837783Y-435904D01*
X838657Y-437946D01*
X839093Y-440279D01*
Y-442613D01*
X838657Y-444946D01*
X837783Y-446988D01*
X836473Y-448738D01*
X834944Y-449904D01*
X833198Y-450196D01*
G01X884039Y-432696D02*
X889498Y-450196D01*
X894957Y-432696D01*
G01X911365Y-450196D02*
X902631D01*
Y-432696D01*
X911365D01*
G01X907871Y-441154D02*
X902631D01*
G01X920131Y-450196D02*
Y-432696D01*
X925590D01*
X927336Y-433571D01*
X928428Y-434738D01*
X928865Y-437071D01*
X928428Y-439405D01*
X927118Y-440863D01*
X925590Y-441738D01*
X920131D01*
G01X925590D02*
X928865Y-450196D01*
G01X941998Y-450779D02*
X941561Y-450488D01*
Y-449904D01*
X941998Y-449613D01*
X942435Y-449904D01*
Y-450488D01*
X941998Y-450779D01*
G01X915748Y-495196D02*
Y-477696D01*
X913128Y-481196D01*
G01Y-495196D02*
X918368D01*
G01X1161715Y-477696D02*
Y-495196D01*
X1152981D01*
G01X1143560Y-493155D02*
X1142031Y-494613D01*
X1140285Y-495196D01*
X1138538Y-494613D01*
X1137010Y-492863D01*
X1135918Y-490238D01*
X1135481Y-487613D01*
Y-484405D01*
X1135918Y-481780D01*
X1137010Y-479446D01*
X1138320Y-478279D01*
X1139848Y-477696D01*
X1141595Y-478279D01*
X1142905Y-479446D01*
X1143778Y-481196D01*
X1144215Y-483530D01*
X1143778Y-485571D01*
X1142686Y-487613D01*
X1141376Y-488780D01*
X1139848Y-489071D01*
X1138102Y-488488D01*
X1136791Y-487029D01*
X1135481Y-484405D01*
G01X1121038Y-486446D02*
X1116671D01*
Y-491696D01*
X1117981Y-493446D01*
X1119510Y-494613D01*
X1121693Y-495196D01*
X1123876Y-494613D01*
X1125405Y-493446D01*
X1126715Y-491696D01*
X1127588Y-489654D01*
X1128025Y-487321D01*
Y-485279D01*
X1127588Y-483530D01*
X1126715Y-481487D01*
X1125405Y-479738D01*
X1124095Y-478571D01*
X1122348Y-477696D01*
X1120820D01*
X1119073Y-478279D01*
X1117763Y-479446D01*
G01X1109870Y-495196D02*
Y-477696D01*
X1099826Y-495196D01*
Y-477696D01*
G01X1092151Y-495196D02*
Y-477696D01*
X1087785D01*
X1086038Y-478571D01*
X1084728Y-479738D01*
X1083636Y-481487D01*
X1082763Y-483530D01*
X1082545Y-486446D01*
X1082763Y-489363D01*
X1083636Y-491405D01*
X1084728Y-493155D01*
X1086038Y-494321D01*
X1087785Y-495196D01*
X1092151D01*
G01X1082981Y-432696D02*
Y-450196D01*
X1091715D01*
G01X1108778D02*
Y-438530D01*
G01Y-440571D02*
X1107905Y-439405D01*
X1106594Y-438821D01*
X1105066Y-438530D01*
X1103538Y-439113D01*
X1102228Y-440279D01*
X1101354Y-442029D01*
X1100918Y-444363D01*
X1101354Y-446696D01*
X1102228Y-448446D01*
X1103538Y-449613D01*
X1105066Y-450196D01*
X1106594Y-449904D01*
X1107905Y-449030D01*
X1108778Y-447863D01*
G01X1117763Y-455446D02*
X1119073Y-456029D01*
X1120820Y-455446D01*
X1121911Y-454280D01*
X1122785Y-452821D01*
X1124094Y-448155D01*
X1126933Y-438530D01*
G01X1119946D02*
X1124094Y-448155D01*
G01X1136573Y-442321D02*
X1143560D01*
X1142905Y-440279D01*
X1141813Y-439113D01*
X1140285Y-438530D01*
X1138756Y-438821D01*
X1137446Y-439696D01*
X1136573Y-441738D01*
X1136136Y-443488D01*
Y-445238D01*
X1136573Y-446988D01*
X1137665Y-448738D01*
X1138975Y-449904D01*
X1140503Y-450196D01*
X1142031Y-449613D01*
X1143560Y-447863D01*
G01X1154291Y-450196D02*
Y-438530D01*
G01Y-440863D02*
X1155383Y-439696D01*
X1156475Y-438821D01*
X1158003Y-438530D01*
X1159094Y-438821D01*
X1160405Y-439696D01*
G01X1312898Y-495196D02*
X1311151Y-494904D01*
X1309623Y-493738D01*
X1308313Y-491988D01*
X1307439Y-489946D01*
X1307003Y-487613D01*
Y-485279D01*
X1307439Y-482946D01*
X1308313Y-480904D01*
X1309623Y-479155D01*
X1311151Y-477988D01*
X1312898Y-477696D01*
X1314644Y-477988D01*
X1316173Y-479155D01*
X1317483Y-480904D01*
X1318357Y-482946D01*
X1318793Y-485279D01*
Y-487613D01*
X1318357Y-489946D01*
X1317483Y-491988D01*
X1316173Y-493738D01*
X1314644Y-494904D01*
X1312898Y-495196D01*
G01X1314644Y-490529D02*
X1317265Y-495196D01*
G01X1325595Y-477696D02*
Y-490238D01*
X1326468Y-492863D01*
X1328215Y-494613D01*
X1330398Y-495196D01*
X1332581Y-494613D01*
X1334328Y-492863D01*
X1335201Y-490238D01*
Y-477696D01*
G01X1345278D02*
X1350518D01*
G01X1347898D02*
Y-495196D01*
G01X1345278D02*
X1350518D01*
G01X1360376D02*
Y-477696D01*
X1370420Y-495196D01*
Y-477696D01*
G01X1387701Y-479155D02*
X1386391Y-478279D01*
X1384863Y-477696D01*
X1383116D01*
X1381151Y-478571D01*
X1379623Y-480029D01*
X1378531Y-481780D01*
X1377658Y-484696D01*
X1377439Y-487321D01*
X1377876Y-489946D01*
X1378531Y-491696D01*
X1379841Y-493446D01*
X1381370Y-494613D01*
X1382898Y-495196D01*
X1384426D01*
X1385955Y-494613D01*
X1387265Y-493738D01*
X1388357Y-492572D01*
G01X1400398Y-495196D02*
Y-487321D01*
X1396031Y-477696D01*
G01X1404765D02*
X1400398Y-487321D01*
G01X1290595Y-450196D02*
Y-432696D01*
X1294961D01*
X1296708Y-433571D01*
X1298018Y-434738D01*
X1299110Y-436487D01*
X1299983Y-438530D01*
X1300201Y-441446D01*
X1299983Y-444363D01*
X1299110Y-446405D01*
X1298018Y-448155D01*
X1296708Y-449321D01*
X1294961Y-450196D01*
X1290595D01*
G01X1309623Y-442321D02*
X1316610D01*
X1315955Y-440279D01*
X1314863Y-439113D01*
X1313335Y-438530D01*
X1311806Y-438821D01*
X1310496Y-439696D01*
X1309623Y-441738D01*
X1309186Y-443488D01*
Y-445238D01*
X1309623Y-446988D01*
X1310715Y-448738D01*
X1312025Y-449904D01*
X1313553Y-450196D01*
X1315081Y-449613D01*
X1316610Y-447863D01*
G01X1327123Y-448155D02*
X1328215Y-449321D01*
X1329743Y-450196D01*
X1331053D01*
X1332363Y-449613D01*
X1333236Y-448738D01*
X1333673Y-447572D01*
X1333455Y-445821D01*
X1332581Y-444946D01*
X1328651Y-443196D01*
X1327778Y-441154D01*
X1328215Y-439696D01*
X1329088Y-438821D01*
X1330398Y-438530D01*
X1331708Y-438821D01*
X1333018Y-439696D01*
G01X1347898Y-438530D02*
Y-450196D01*
G01Y-433863D02*
X1347461Y-433571D01*
Y-432988D01*
X1347898Y-432696D01*
X1348335Y-432988D01*
Y-433571D01*
X1347898Y-433863D01*
G01X1362341Y-454571D02*
X1363870Y-455738D01*
X1365616Y-456029D01*
X1367144Y-455738D01*
X1368455Y-454280D01*
X1369328Y-452238D01*
Y-438530D01*
G01Y-440863D02*
X1368455Y-439696D01*
X1367144Y-438821D01*
X1365616Y-438530D01*
X1363870Y-439113D01*
X1362778Y-440279D01*
X1361904Y-442321D01*
X1361468Y-444363D01*
X1361686Y-446113D01*
X1362560Y-448155D01*
X1363870Y-449613D01*
X1365616Y-450196D01*
X1366926Y-449904D01*
X1368455Y-448738D01*
X1369328Y-447572D01*
G01X1379186Y-450196D02*
Y-438530D01*
G01Y-441446D02*
X1380060Y-439988D01*
X1381370Y-438821D01*
X1383116Y-438530D01*
X1384644Y-438821D01*
X1385955Y-439988D01*
X1386610Y-442029D01*
Y-450196D01*
G01X1397123Y-442321D02*
X1404110D01*
X1403455Y-440279D01*
X1402363Y-439113D01*
X1400835Y-438530D01*
X1399306Y-438821D01*
X1397996Y-439696D01*
X1397123Y-441738D01*
X1396686Y-443488D01*
Y-445238D01*
X1397123Y-446988D01*
X1398215Y-448738D01*
X1399525Y-449904D01*
X1401053Y-450196D01*
X1402581Y-449613D01*
X1404110Y-447863D01*
G01X1414841Y-450196D02*
Y-438530D01*
G01Y-440863D02*
X1415933Y-439696D01*
X1417025Y-438821D01*
X1418553Y-438530D01*
X1419644Y-438821D01*
X1420955Y-439696D01*
G01X1461598Y-477696D02*
X1459851Y-478279D01*
X1458541Y-479738D01*
X1457668Y-481487D01*
X1457013Y-483821D01*
X1456795Y-486446D01*
X1457013Y-489071D01*
X1457668Y-491405D01*
X1458541Y-493155D01*
X1459851Y-494613D01*
X1461598Y-495196D01*
X1463344Y-494613D01*
X1464655Y-493155D01*
X1465528Y-491405D01*
X1466183Y-489071D01*
X1466401Y-486446D01*
X1466183Y-483821D01*
X1465528Y-481487D01*
X1464655Y-479738D01*
X1463344Y-478279D01*
X1461598Y-477696D01*
G01X1474950Y-487905D02*
X1476478Y-485863D01*
X1477788Y-484696D01*
X1479535Y-484113D01*
X1481063Y-484696D01*
X1482155Y-485863D01*
X1483028Y-487613D01*
X1483246Y-489654D01*
X1483028Y-491405D01*
X1482155Y-493155D01*
X1480844Y-494613D01*
X1479316Y-495196D01*
X1477570Y-494613D01*
X1476041Y-492863D01*
X1475168Y-490238D01*
X1474950Y-487321D01*
X1475386Y-483530D01*
X1476041Y-481487D01*
X1477133Y-479446D01*
X1478661Y-477988D01*
X1480190Y-477696D01*
X1481718Y-478279D01*
X1482810Y-479738D01*
G01X1492668Y-495779D02*
X1500528Y-477696D01*
G01X1514098D02*
X1512351Y-478279D01*
X1511041Y-479738D01*
X1510168Y-481487D01*
X1509513Y-483821D01*
X1509295Y-486446D01*
X1509513Y-489071D01*
X1510168Y-491405D01*
X1511041Y-493155D01*
X1512351Y-494613D01*
X1514098Y-495196D01*
X1515844Y-494613D01*
X1517155Y-493155D01*
X1518028Y-491405D01*
X1518683Y-489071D01*
X1518901Y-486446D01*
X1518683Y-483821D01*
X1518028Y-481487D01*
X1517155Y-479738D01*
X1515844Y-478279D01*
X1514098Y-477696D01*
G01X1527886Y-493155D02*
X1529415Y-494613D01*
X1531161Y-495196D01*
X1532908Y-494613D01*
X1534436Y-492863D01*
X1535528Y-490238D01*
X1535965Y-487613D01*
Y-484405D01*
X1535528Y-481780D01*
X1534436Y-479446D01*
X1533126Y-478279D01*
X1531598Y-477696D01*
X1529851Y-478279D01*
X1528541Y-479446D01*
X1527668Y-481196D01*
X1527231Y-483530D01*
X1527668Y-485571D01*
X1528760Y-487613D01*
X1530070Y-488780D01*
X1531598Y-489071D01*
X1533344Y-488488D01*
X1534655Y-487029D01*
X1535965Y-484405D01*
G01X1545168Y-495779D02*
X1553028Y-477696D01*
G01X1562450Y-480613D02*
X1563760Y-478863D01*
X1565288Y-477988D01*
X1567035Y-477696D01*
X1569218Y-478279D01*
X1570746Y-479738D01*
X1571183Y-481487D01*
X1570965Y-483238D01*
X1570091Y-484696D01*
X1565725Y-487613D01*
X1563760Y-489654D01*
X1562450Y-492572D01*
X1562013Y-495196D01*
X1571183D01*
G01X1584098Y-477696D02*
X1582351Y-478279D01*
X1581041Y-479738D01*
X1580168Y-481487D01*
X1579513Y-483821D01*
X1579295Y-486446D01*
X1579513Y-489071D01*
X1580168Y-491405D01*
X1581041Y-493155D01*
X1582351Y-494613D01*
X1584098Y-495196D01*
X1585844Y-494613D01*
X1587155Y-493155D01*
X1588028Y-491405D01*
X1588683Y-489071D01*
X1588901Y-486446D01*
X1588683Y-483821D01*
X1588028Y-481487D01*
X1587155Y-479738D01*
X1585844Y-478279D01*
X1584098Y-477696D01*
G01X1601598Y-495196D02*
Y-477696D01*
X1598978Y-481196D01*
G01Y-495196D02*
X1604218D01*
G01X1618661D02*
X1619098Y-491405D01*
X1619753Y-488196D01*
X1620626Y-485279D01*
X1621718Y-482071D01*
X1623465Y-477696D01*
X1614731D01*
G01X1509295Y-450196D02*
Y-432696D01*
X1513661D01*
X1515408Y-433571D01*
X1516718Y-434738D01*
X1517810Y-436487D01*
X1518683Y-438530D01*
X1518901Y-441446D01*
X1518683Y-444363D01*
X1517810Y-446405D01*
X1516718Y-448155D01*
X1515408Y-449321D01*
X1513661Y-450196D01*
X1509295D01*
G01X1535528D02*
Y-438530D01*
G01Y-440571D02*
X1534655Y-439405D01*
X1533344Y-438821D01*
X1531816Y-438530D01*
X1530288Y-439113D01*
X1528978Y-440279D01*
X1528104Y-442029D01*
X1527668Y-444363D01*
X1528104Y-446696D01*
X1528978Y-448446D01*
X1530288Y-449613D01*
X1531816Y-450196D01*
X1533344Y-449904D01*
X1534655Y-449030D01*
X1535528Y-447863D01*
G01X1549098Y-432696D02*
Y-450196D01*
G01X1546041Y-438530D02*
X1552155D01*
G01X1563323Y-442321D02*
X1570310D01*
X1569655Y-440279D01*
X1568563Y-439113D01*
X1567035Y-438530D01*
X1565506Y-438821D01*
X1564196Y-439696D01*
X1563323Y-441738D01*
X1562886Y-443488D01*
Y-445238D01*
X1563323Y-446988D01*
X1564415Y-448738D01*
X1565725Y-449904D01*
X1567253Y-450196D01*
X1568781Y-449613D01*
X1570310Y-447863D01*
M02*
